FILE_TYPE = MACRO_DRAWING;
SET COLOR_WIRE YELLOW;
SET COLOR_PROP MONO;
SET COLOR_DOT WHITE;
SET COLOR_ARC YELLOW;
SET COLOR_BODY GREEN;
SET COLOR_NOTE MONO;
SET PROP_DISPLAY VALUE;
SET PAGE_NUMBER P185;
FORCEADD OFFPAGE..1
(-3575 2100);
FORCEPROP 2 LAST $XR0 116 
J 0
(-3857 2100);
DISPLAY 0.638298 (-3857 2100);
PAINT MONO (-3857 2100);
FORCEPROP 2 LAST PATH I100
J 0
(-3825 2150);
DISPLAY 1.021277 (-3825 2150);
PAINT ORANGE (-3825 2150);
DISPLAY INVISIBLE (-3825 2150);
FORCEPROP 2 LAST CDS_LIB mstr_standard
J 0
(-3575 2100);
PAINT ORANGE (-3575 2100);
DISPLAY INVISIBLE (-3575 2100);
FORCEPROP 1 LAST COMMENT_BODY TRUE
J 0
(-3450 2000);
DISPLAY 0.872340 (-3450 2000);
PAINT GREEN (-3450 2000);
DISPLAY INVISIBLE (-3450 2000);
FORCEPROP 1 LAST OFFPAGE TRUE
J 0
(-3250 1975);
DISPLAY 0.872340 (-3250 1975);
PAINT GREEN (-3250 1975);
DISPLAY INVISIBLE (-3250 1975);
FORCEADD OFFPAGE..1
(-3575 1825);
FORCEPROP 2 LAST $XR0 116 
J 0
(-3857 1825);
DISPLAY 0.638298 (-3857 1825);
PAINT MONO (-3857 1825);
FORCEPROP 2 LAST PATH I101
J 0
(-3825 1875);
DISPLAY 1.021277 (-3825 1875);
PAINT ORANGE (-3825 1875);
DISPLAY INVISIBLE (-3825 1875);
FORCEPROP 2 LAST CDS_LIB mstr_standard
J 0
(-3575 1825);
PAINT ORANGE (-3575 1825);
DISPLAY INVISIBLE (-3575 1825);
FORCEPROP 1 LAST COMMENT_BODY TRUE
J 0
(-3450 1725);
DISPLAY 0.872340 (-3450 1725);
PAINT GREEN (-3450 1725);
DISPLAY INVISIBLE (-3450 1725);
FORCEPROP 1 LAST OFFPAGE TRUE
J 0
(-3250 1700);
DISPLAY 0.872340 (-3250 1700);
PAINT GREEN (-3250 1700);
DISPLAY INVISIBLE (-3250 1700);
FORCEADD OFFPAGE..1
(-3575 1600);
FORCEPROP 2 LAST $XR0 116 
J 0
(-3857 1600);
DISPLAY 0.638298 (-3857 1600);
PAINT MONO (-3857 1600);
FORCEPROP 2 LAST PATH I102
J 0
(-3825 1650);
DISPLAY 1.021277 (-3825 1650);
PAINT ORANGE (-3825 1650);
DISPLAY INVISIBLE (-3825 1650);
FORCEPROP 2 LAST CDS_LIB mstr_standard
J 0
(-3575 1600);
PAINT ORANGE (-3575 1600);
DISPLAY INVISIBLE (-3575 1600);
FORCEPROP 1 LAST COMMENT_BODY TRUE
J 0
(-3450 1500);
DISPLAY 0.872340 (-3450 1500);
PAINT GREEN (-3450 1500);
DISPLAY INVISIBLE (-3450 1500);
FORCEPROP 1 LAST OFFPAGE TRUE
J 0
(-3250 1475);
DISPLAY 0.872340 (-3250 1475);
PAINT GREEN (-3250 1475);
DISPLAY INVISIBLE (-3250 1475);
FORCEADD OFFPAGE..1
(-3575 1375);
FORCEPROP 2 LAST $XR0 116 
J 0
(-3857 1375);
DISPLAY 0.638298 (-3857 1375);
PAINT MONO (-3857 1375);
FORCEPROP 2 LAST PATH I103
J 0
(-3825 1425);
DISPLAY 1.021277 (-3825 1425);
PAINT ORANGE (-3825 1425);
DISPLAY INVISIBLE (-3825 1425);
FORCEPROP 2 LAST CDS_LIB mstr_standard
J 0
(-3575 1375);
PAINT ORANGE (-3575 1375);
DISPLAY INVISIBLE (-3575 1375);
FORCEPROP 1 LAST COMMENT_BODY TRUE
J 0
(-3450 1275);
DISPLAY 0.872340 (-3450 1275);
PAINT GREEN (-3450 1275);
DISPLAY INVISIBLE (-3450 1275);
FORCEPROP 1 LAST OFFPAGE TRUE
J 0
(-3250 1250);
DISPLAY 0.872340 (-3250 1250);
PAINT GREEN (-3250 1250);
DISPLAY INVISIBLE (-3250 1250);
FORCEADD OFFPAGE..5
(-3575 1175);
FORCEPROP 2 LAST $XR0 116 
J 0
(-3830 1175);
DISPLAY 0.638298 (-3830 1175);
PAINT MONO (-3830 1175);
FORCEPROP 2 LAST PATH I104
J 0
(-3850 1225);
DISPLAY 1.021277 (-3850 1225);
PAINT ORANGE (-3850 1225);
DISPLAY INVISIBLE (-3850 1225);
FORCEPROP 2 LAST CDS_LIB mstr_standard
J 0
(-3575 1175);
PAINT ORANGE (-3575 1175);
DISPLAY INVISIBLE (-3575 1175);
FORCEPROP 1 LAST COMMENT_BODY TRUE
J 0
(-3475 1100);
DISPLAY 0.872340 (-3475 1100);
PAINT GREEN (-3475 1100);
DISPLAY INVISIBLE (-3475 1100);
FORCEPROP 1 LAST OFFPAGE TRUE
J 0
(-3250 1050);
DISPLAY 0.872340 (-3250 1050);
PAINT GREEN (-3250 1050);
DISPLAY INVISIBLE (-3250 1050);
FORCEADD RES..1
(-2600 950);
FORCEPROP 1 LAST WATTAGE 1/16W
J 2
(-2250 950);
DISPLAY 0.617021 (-2250 950);
PAINT SKYBLUE (-2250 950);
FORCEPROP 1 LAST PACK_TYPE 0402
J 2
(-2125 950);
DISPLAY 0.617021 (-2125 950);
PAINT SKYBLUE (-2125 950);
FORCEPROP 1 LAST MATERIAL CHIP
J 0
(-2475 950);
DISPLAY 0.617021 (-2475 950);
PAINT SKYBLUE (-2475 950);
FORCEPROP 1 LASTPIN (-2500 950) $PN 2
J 0
(-2538 962);
DISPLAY 0.617021 (-2538 962);
PAINT ORANGE (-2538 962);
FORCEPROP 1 LAST PART_NUMBER G21497-005
J 2
(-1850 950);
DISPLAY 0.617021 (-1850 950);
PAINT BLUE (-1850 950);
FORCEPROP 1 LAST LOCATION R8F18
J 0
(-3100 950);
DISPLAY 0.617021 (-3100 950);
PAINT AQUA (-3100 950);
FORCEPROP 1 LASTPIN (-2700 950) $PN 1
J 0
(-2688 962);
DISPLAY 0.617021 (-2688 962);
PAINT ORANGE (-2688 962);
FORCEPROP 1 LAST VALUE 0.0
J 1
(-2900 950);
DISPLAY 0.617021 (-2900 950);
PAINT SKYBLUE (-2900 950);
FORCEPROP 1 LAST TOLERANCE 5%
J 0
(-2800 950);
DISPLAY 0.617021 (-2800 950);
PAINT SKYBLUE (-2800 950);
FORCEPROP 0 LAST GROUP M2_PCIE
J 0
(-2700 1000);
DISPLAY 0.638298 (-2700 1000);
PAINT BROWN (-2700 1000);
DISPLAY BOTH (-2700 1000);
FORCEPROP 2 LAST CDS_LOCATION R8F18
J 0
(-3100 950);
DISPLAY 0.617021 (-3100 950);
PAINT AQUA (-3100 950);
DISPLAY INVISIBLE (-3100 950);
FORCEPROP 1 LAST PATH I105
J 0
(-2650 1100);
DISPLAY 0.978723 (-2650 1100);
PAINT WHITE (-2650 1100);
DISPLAY INVISIBLE (-2650 1100);
FORCEPROP 2 LAST SEC 1
J 0
(-2650 1150);
DISPLAY 0.680851 (-2650 1150);
PAINT MONO (-2650 1150);
DISPLAY INVISIBLE (-2650 1150);
FORCEPROP 2 LAST CDS_LIB mstr_discrete
J 0
(-2600 950);
PAINT ORANGE (-2600 950);
DISPLAY INVISIBLE (-2600 950);
FORCEPROP 2 LAST SEC_TYPE 0402
J 0
(-2650 1150);
DISPLAY 1.021277 (-2650 1150);
PAINT ORANGE (-2650 1150);
DISPLAY INVISIBLE (-2650 1150);
FORCEPROP 0 LAST ROOM M_2
J 0
(-1850 1000);
DISPLAY 1.021277 (-1850 1000);
PAINT ORANGE (-1850 1000);
DISPLAY INVISIBLE (-1850 1000);
FORCEPROP 0 LAST BOM_COST ST_FLASH
J 0
(-1850 1050);
DISPLAY 1.021277 (-1850 1050);
PAINT ORANGE (-1850 1050);
DISPLAY INVISIBLE (-1850 1050);
FORCEADD RES..1
(-2575 500);
FORCEPROP 1 LAST MATERIAL CHIP
J 0
(-2450 500);
DISPLAY 0.617021 (-2450 500);
PAINT SKYBLUE (-2450 500);
FORCEPROP 1 LAST VALUE 0.0
J 1
(-2925 500);
DISPLAY 0.617021 (-2925 500);
PAINT SKYBLUE (-2925 500);
FORCEPROP 1 LAST LOCATION R8F21
J 0
(-3075 500);
DISPLAY 0.617021 (-3075 500);
PAINT AQUA (-3075 500);
FORCEPROP 1 LAST WATTAGE 1/16W
J 2
(-2225 500);
DISPLAY 0.617021 (-2225 500);
PAINT SKYBLUE (-2225 500);
FORCEPROP 1 LAST TOLERANCE 5%
J 0
(-2750 500);
DISPLAY 0.617021 (-2750 500);
PAINT SKYBLUE (-2750 500);
FORCEPROP 1 LASTPIN (-2675 500) $PN 1
J 0
(-2663 512);
DISPLAY 0.617021 (-2663 512);
PAINT ORANGE (-2663 512);
FORCEPROP 1 LASTPIN (-2475 500) $PN 2
J 0
(-2513 512);
DISPLAY 0.617021 (-2513 512);
PAINT ORANGE (-2513 512);
FORCEPROP 1 LAST PACK_TYPE 0402
J 2
(-2100 500);
DISPLAY 0.617021 (-2100 500);
PAINT SKYBLUE (-2100 500);
FORCEPROP 1 LAST PART_NUMBER G21497-005
J 2
(-1825 500);
DISPLAY 0.617021 (-1825 500);
PAINT BLUE (-1825 500);
FORCEPROP 0 LAST GROUP M2_PCIE
J 0
(-2650 550);
DISPLAY 0.638298 (-2650 550);
PAINT BROWN (-2650 550);
DISPLAY BOTH (-2650 550);
FORCEPROP 2 LAST CDS_LOCATION R8F21
J 0
(-3075 500);
DISPLAY 0.617021 (-3075 500);
PAINT AQUA (-3075 500);
DISPLAY INVISIBLE (-3075 500);
FORCEPROP 2 LAST CDS_LIB mstr_discrete
J 0
(-2575 500);
PAINT ORANGE (-2575 500);
DISPLAY INVISIBLE (-2575 500);
FORCEPROP 1 LAST PATH I106
J 0
(-2625 650);
DISPLAY 0.978723 (-2625 650);
PAINT WHITE (-2625 650);
DISPLAY INVISIBLE (-2625 650);
FORCEPROP 2 LAST SEC_TYPE 0402
J 0
(-2625 700);
DISPLAY 1.021277 (-2625 700);
PAINT ORANGE (-2625 700);
DISPLAY INVISIBLE (-2625 700);
FORCEPROP 2 LAST SEC 1
J 0
(-2625 700);
DISPLAY 0.680851 (-2625 700);
PAINT MONO (-2625 700);
DISPLAY INVISIBLE (-2625 700);
FORCEPROP 0 LAST BOM_COST ST_FLASH
J 0
(-1825 600);
DISPLAY 1.021277 (-1825 600);
PAINT ORANGE (-1825 600);
DISPLAY INVISIBLE (-1825 600);
FORCEPROP 0 LAST ROOM M_2
J 0
(-1825 550);
DISPLAY 1.021277 (-1825 550);
PAINT ORANGE (-1825 550);
DISPLAY INVISIBLE (-1825 550);
FORCEADD OFFPAGE..5
(-3575 950);
FORCEPROP 2 LAST $XR0 116 
J 0
(-3830 950);
DISPLAY 0.638298 (-3830 950);
PAINT MONO (-3830 950);
FORCEPROP 2 LAST PATH I107
J 0
(-3850 1000);
DISPLAY 1.021277 (-3850 1000);
PAINT ORANGE (-3850 1000);
DISPLAY INVISIBLE (-3850 1000);
FORCEPROP 1 LAST COMMENT_BODY TRUE
J 0
(-3475 875);
DISPLAY 0.872340 (-3475 875);
PAINT GREEN (-3475 875);
DISPLAY INVISIBLE (-3475 875);
FORCEPROP 1 LAST OFFPAGE TRUE
J 0
(-3250 825);
DISPLAY 0.872340 (-3250 825);
PAINT GREEN (-3250 825);
DISPLAY INVISIBLE (-3250 825);
FORCEPROP 2 LAST CDS_LIB mstr_standard
J 0
(-3575 950);
PAINT ORANGE (-3575 950);
DISPLAY INVISIBLE (-3575 950);
FORCEADD OFFPAGE..5
(-3575 750);
FORCEPROP 2 LAST $XR0 116 
J 0
(-3830 750);
DISPLAY 0.638298 (-3830 750);
PAINT MONO (-3830 750);
FORCEPROP 2 LAST PATH I108
J 0
(-3850 800);
DISPLAY 1.021277 (-3850 800);
PAINT ORANGE (-3850 800);
DISPLAY INVISIBLE (-3850 800);
FORCEPROP 2 LAST CDS_LIB mstr_standard
J 0
(-3575 750);
PAINT ORANGE (-3575 750);
DISPLAY INVISIBLE (-3575 750);
FORCEPROP 1 LAST COMMENT_BODY TRUE
J 0
(-3475 675);
DISPLAY 0.872340 (-3475 675);
PAINT GREEN (-3475 675);
DISPLAY INVISIBLE (-3475 675);
FORCEPROP 1 LAST OFFPAGE TRUE
J 0
(-3250 625);
DISPLAY 0.872340 (-3250 625);
PAINT GREEN (-3250 625);
DISPLAY INVISIBLE (-3250 625);
FORCEADD OFFPAGE..5
(-3575 500);
FORCEPROP 2 LAST $XR0 116 
J 0
(-3830 500);
DISPLAY 0.638298 (-3830 500);
PAINT MONO (-3830 500);
FORCEPROP 2 LAST PATH I109
J 0
(-3850 550);
DISPLAY 1.021277 (-3850 550);
PAINT ORANGE (-3850 550);
DISPLAY INVISIBLE (-3850 550);
FORCEPROP 2 LAST CDS_LIB mstr_standard
J 0
(-3575 500);
PAINT ORANGE (-3575 500);
DISPLAY INVISIBLE (-3575 500);
FORCEPROP 1 LAST COMMENT_BODY TRUE
J 0
(-3475 425);
DISPLAY 0.872340 (-3475 425);
PAINT GREEN (-3475 425);
DISPLAY INVISIBLE (-3475 425);
FORCEPROP 1 LAST OFFPAGE TRUE
J 0
(-3250 375);
DISPLAY 0.872340 (-3250 375);
PAINT GREEN (-3250 375);
DISPLAY INVISIBLE (-3250 375);
FORCEADD TTL1G07_A..1
(-5150 2500);
FORCEPROP 2 LASTPIN (-5250 2500) $PN 2
J 2
(-5260 2510);
DISPLAY 0.617021 (-5260 2510);
PAINT ORANGE (-5260 2510);
FORCEPROP 1 LAST VALUE 74LVC1G07
J 1
(-5150 2600);
DISPLAY 0.617021 (-5150 2600);
PAINT SKYBLUE (-5150 2600);
FORCEPROP 1 LAST MATERIAL IC
J 0
(-5200 2650);
DISPLAY 0.617021 (-5200 2650);
PAINT SKYBLUE (-5200 2650);
FORCEPROP 1 LAST LOCATION U2P1
J 0
(-5200 2700);
DISPLAY 0.617021 (-5200 2700);
PAINT AQUA (-5200 2700);
FORCEPROP 2 LASTPIN (-5000 2500) $PN 4
J 0
(-4990 2510);
DISPLAY 0.617021 (-4990 2510);
PAINT ORANGE (-4990 2510);
FORCEPROP 1 LAST POWER_GROUP VCC=P3V3_STBY;GND=GND
J 1
(-5200 2310);
DISPLAY 0.617021 (-5200 2310);
PAINT ORANGE (-5200 2310);
FORCEPROP 1 LAST PART_NUMBER C88419-001
J 0
(-5200 2365);
DISPLAY 0.617021 (-5200 2365);
PAINT BLUE (-5200 2365);
FORCEPROP 0 LAST ROOM M_2
J 0
(-5200 2800);
DISPLAY 1.021277 (-5200 2800);
PAINT ORANGE (-5200 2800);
DISPLAY INVISIBLE (-5200 2800);
FORCEPROP 0 LAST BOM_COST ST_FLASH
J 0
(-5200 2900);
DISPLAY 1.021277 (-5200 2900);
PAINT ORANGE (-5200 2900);
DISPLAY INVISIBLE (-5200 2900);
FORCEPROP 2 LAST SEC_TYPE SOP
J 0
(-5200 2750);
DISPLAY 1.021277 (-5200 2750);
PAINT ORANGE (-5200 2750);
DISPLAY INVISIBLE (-5200 2750);
FORCEPROP 1 LAST PACK_TYPE SOP
J 0
(-5200 2750);
DISPLAY 0.978723 (-5200 2750);
PAINT SKYBLUE (-5200 2750);
DISPLAY INVISIBLE (-5200 2750);
FORCEPROP 2 LAST CDS_LIB mstr_ttl
J 0
(-5150 2500);
PAINT ORANGE (-5150 2500);
DISPLAY INVISIBLE (-5150 2500);
FORCEPROP 1 LAST PATH I110
J 0
(-5100 2550);
DISPLAY 0.978723 (-5100 2550);
PAINT WHITE (-5100 2550);
DISPLAY INVISIBLE (-5100 2550);
FORCEPROP 2 LAST SEC 1
J 0
(-5200 2750);
DISPLAY 0.680851 (-5200 2750);
PAINT MONO (-5200 2750);
DISPLAY INVISIBLE (-5200 2750);
FORCEADD RES..2
(-5500 2700);
FORCEPROP 1 LAST VALUE 10.0K
J 0
(-5455 2775);
DISPLAY 0.617021 (-5455 2775);
PAINT SKYBLUE (-5455 2775);
FORCEPROP 1 LAST TOLERANCE 1%
J 0
(-5455 2725);
DISPLAY 0.617021 (-5455 2725);
PAINT SKYBLUE (-5455 2725);
FORCEPROP 1 LASTPIN (-5500 2600) $PN 2
J 0
(-5495 2610);
DISPLAY 0.617021 (-5495 2610);
PAINT ORANGE (-5495 2610);
FORCEPROP 1 LASTPIN (-5500 2800) $PN 1
J 0
(-5495 2762);
DISPLAY 0.617021 (-5495 2762);
PAINT ORANGE (-5495 2762);
FORCEPROP 1 LAST MATERIAL CHIP
J 0
(-5460 2625);
DISPLAY 0.617021 (-5460 2625);
PAINT SKYBLUE (-5460 2625);
FORCEPROP 1 LAST PACK_TYPE 0402
J 0
(-5460 2525);
DISPLAY 0.617021 (-5460 2525);
PAINT SKYBLUE (-5460 2525);
FORCEPROP 1 LAST PART_NUMBER G21796-016
J 0
(-5460 2575);
DISPLAY 0.617021 (-5460 2575);
PAINT BLUE (-5460 2575);
FORCEPROP 1 LAST LOCATION R2P15
J 0
(-5455 2825);
DISPLAY 0.617021 (-5455 2825);
PAINT AQUA (-5455 2825);
FORCEPROP 1 LAST WATTAGE 1/16W
J 0
(-5460 2675);
DISPLAY 0.617021 (-5460 2675);
PAINT SKYBLUE (-5460 2675);
FORCEPROP 2 LAST CDS_LIB mstr_discrete
J 0
(-5500 2700);
PAINT ORANGE (-5500 2700);
DISPLAY INVISIBLE (-5500 2700);
FORCEPROP 1 LAST PATH I111
J 0
(-5450 2875);
DISPLAY 0.978723 (-5450 2875);
PAINT WHITE (-5450 2875);
DISPLAY INVISIBLE (-5450 2875);
FORCEPROP 2 LAST SEC 1
J 0
(-5450 2925);
DISPLAY 0.680851 (-5450 2925);
PAINT MONO (-5450 2925);
DISPLAY INVISIBLE (-5450 2925);
FORCEPROP 0 LAST ROOM M_2
J 0
(-5450 2925);
DISPLAY 1.021277 (-5450 2925);
PAINT ORANGE (-5450 2925);
DISPLAY INVISIBLE (-5450 2925);
FORCEPROP 2 LAST SEC_TYPE 0402
J 0
(-5450 2925);
DISPLAY 1.021277 (-5450 2925);
PAINT ORANGE (-5450 2925);
DISPLAY INVISIBLE (-5450 2925);
FORCEPROP 0 LAST BOM_COST ST_FLASH
J 0
(-5450 3025);
DISPLAY 1.021277 (-5450 3025);
PAINT ORANGE (-5450 3025);
DISPLAY INVISIBLE (-5450 3025);
FORCEADD P3V3..1
(-5500 2900);
FORCEPROP 3 LASTPIN (-5500 2850) SIG_NAME P3V3\g
J 0
(-5490 2860);
DISPLAY 0.659574 (-5490 2860);
PAINT MONO (-5490 2860);
DISPLAY INVISIBLE (-5490 2860);
FORCEPROP 1 LAST HDL_POWER P3V3
J 0
(-5825 2775);
DISPLAY 0.872340 (-5825 2775);
PAINT ORANGE (-5825 2775);
DISPLAY INVISIBLE (-5825 2775);
FORCEPROP 1 LAST PATH I112
J 0
(-5455 2902);
DISPLAY 0.340426 (-5455 2902);
PAINT GREEN (-5455 2902);
DISPLAY INVISIBLE (-5455 2902);
FORCEPROP 1 LAST BODY_TYPE PLUMBING
J 0
(-5545 2857);
DISPLAY 0.340426 (-5545 2857);
PAINT GREEN (-5545 2857);
DISPLAY INVISIBLE (-5545 2857);
FORCEPROP 2 LAST CDS_LIB mstr_symbols
J 0
(-5500 2900);
PAINT ORANGE (-5500 2900);
DISPLAY INVISIBLE (-5500 2900);
FORCEPROP 1 LAST SIZE 1B
J 0
(-5455 2922);
DISPLAY 0.340426 (-5455 2922);
PAINT GREEN (-5455 2922);
DISPLAY INVISIBLE (-5455 2922);
FORCEPROP 1 LAST VOLTAGE 3.3V
J 0
(-5545 2857);
DISPLAY 0.340426 (-5545 2857);
PAINT SKYBLUE (-5545 2857);
DISPLAY INVISIBLE (-5545 2857);
FORCEADD RES..2
(-4400 2800);
FORCEPROP 1 LAST LOCATION R2P16
J 0
(-4355 2925);
DISPLAY 0.617021 (-4355 2925);
PAINT AQUA (-4355 2925);
FORCEPROP 1 LASTPIN (-4400 2900) $PN 1
J 0
(-4395 2862);
DISPLAY 0.617021 (-4395 2862);
PAINT ORANGE (-4395 2862);
FORCEPROP 1 LAST VALUE 10.0K
J 0
(-4355 2875);
DISPLAY 0.617021 (-4355 2875);
PAINT SKYBLUE (-4355 2875);
FORCEPROP 1 LASTPIN (-4400 2700) $PN 2
J 0
(-4395 2710);
DISPLAY 0.617021 (-4395 2710);
PAINT ORANGE (-4395 2710);
FORCEPROP 1 LAST MATERIAL CHIP
J 0
(-4360 2725);
DISPLAY 0.617021 (-4360 2725);
PAINT SKYBLUE (-4360 2725);
FORCEPROP 1 LAST PACK_TYPE 0402
J 0
(-4360 2625);
DISPLAY 0.617021 (-4360 2625);
PAINT SKYBLUE (-4360 2625);
FORCEPROP 1 LAST TOLERANCE 1%
J 0
(-4355 2825);
DISPLAY 0.617021 (-4355 2825);
PAINT SKYBLUE (-4355 2825);
FORCEPROP 1 LAST WATTAGE 1/16W
J 0
(-4360 2775);
DISPLAY 0.617021 (-4360 2775);
PAINT SKYBLUE (-4360 2775);
FORCEPROP 1 LAST PART_NUMBER G21796-016
J 0
(-4360 2675);
DISPLAY 0.617021 (-4360 2675);
PAINT BLUE (-4360 2675);
FORCEPROP 2 LAST CDS_LIB mstr_discrete
J 0
(-4400 2800);
PAINT ORANGE (-4400 2800);
DISPLAY INVISIBLE (-4400 2800);
FORCEPROP 2 LAST SEC 1
J 0
(-4350 3025);
DISPLAY 0.680851 (-4350 3025);
PAINT MONO (-4350 3025);
DISPLAY INVISIBLE (-4350 3025);
FORCEPROP 1 LAST PATH I113
J 0
(-4350 2975);
DISPLAY 0.978723 (-4350 2975);
PAINT WHITE (-4350 2975);
DISPLAY INVISIBLE (-4350 2975);
FORCEPROP 0 LAST ROOM M_2
J 0
(-4350 3025);
DISPLAY 1.021277 (-4350 3025);
PAINT ORANGE (-4350 3025);
DISPLAY INVISIBLE (-4350 3025);
FORCEPROP 2 LAST SEC_TYPE 0402
J 0
(-4350 3025);
DISPLAY 1.021277 (-4350 3025);
PAINT ORANGE (-4350 3025);
DISPLAY INVISIBLE (-4350 3025);
FORCEPROP 0 LAST BOM_COST ST_FLASH
J 0
(-4350 3125);
DISPLAY 1.021277 (-4350 3125);
PAINT ORANGE (-4350 3125);
DISPLAY INVISIBLE (-4350 3125);
FORCEADD P3V3_STBY..1
(-4400 3000);
FORCEPROP 3 LASTPIN (-4400 2950) SIG_NAME P3V3_STBY\g
J 0
(-4390 2960);
DISPLAY 0.659574 (-4390 2960);
PAINT MONO (-4390 2960);
DISPLAY INVISIBLE (-4390 2960);
FORCEPROP 1 LAST HDL_POWER P3V3_STBY
J 0
(-4700 2875);
DISPLAY 0.872340 (-4700 2875);
PAINT ORANGE (-4700 2875);
DISPLAY INVISIBLE (-4700 2875);
FORCEPROP 1 LAST VOLTAGE 3.3V
J 0
(-4445 2957);
DISPLAY 0.340426 (-4445 2957);
PAINT SKYBLUE (-4445 2957);
DISPLAY INVISIBLE (-4445 2957);
FORCEPROP 2 LAST CDS_LIB mstr_symbols
J 0
(-4400 3000);
PAINT ORANGE (-4400 3000);
DISPLAY INVISIBLE (-4400 3000);
FORCEPROP 1 LAST BODY_TYPE PLUMBING
J 0
(-4445 2957);
DISPLAY 0.340426 (-4445 2957);
PAINT GREEN (-4445 2957);
DISPLAY INVISIBLE (-4445 2957);
FORCEPROP 1 LAST SIZE 1B
J 0
(-4355 3022);
DISPLAY 0.340426 (-4355 3022);
PAINT GREEN (-4355 3022);
DISPLAY INVISIBLE (-4355 3022);
FORCEPROP 1 LAST PATH I114
J 0
(-4355 3002);
DISPLAY 0.340426 (-4355 3002);
PAINT GREEN (-4355 3002);
DISPLAY INVISIBLE (-4355 3002);
FORCEADD RES..1
(-4250 2500);
FORCEPROP 1 LAST PART_NUMBER G21497-005
J 0
(-4300 2600);
DISPLAY 0.617021 (-4300 2600);
PAINT BLUE (-4300 2600);
FORCEPROP 1 LAST LOCATION R2P14
J 0
(-4300 2550);
DISPLAY 0.617021 (-4300 2550);
PAINT AQUA (-4300 2550);
FORCEPROP 1 LASTPIN (-4350 2500) $PN 1
J 0
(-4338 2512);
DISPLAY 0.617021 (-4338 2512);
PAINT ORANGE (-4338 2512);
FORCEPROP 1 LAST MATERIAL CHIP
J 0
(-4250 2350);
DISPLAY 0.617021 (-4250 2350);
PAINT SKYBLUE (-4250 2350);
FORCEPROP 1 LASTPIN (-4150 2500) $PN 2
J 0
(-4188 2512);
DISPLAY 0.617021 (-4188 2512);
PAINT ORANGE (-4188 2512);
FORCEPROP 1 LAST WATTAGE 1/16W
J 2
(-4275 2350);
DISPLAY 0.617021 (-4275 2350);
PAINT SKYBLUE (-4275 2350);
FORCEPROP 1 LAST VALUE 0.0
J 2
(-4275 2400);
DISPLAY 0.617021 (-4275 2400);
PAINT SKYBLUE (-4275 2400);
FORCEPROP 1 LAST TOLERANCE 5%
J 0
(-4250 2400);
DISPLAY 0.617021 (-4250 2400);
PAINT SKYBLUE (-4250 2400);
FORCEPROP 1 LAST PACK_TYPE 0402
J 0
(-4000 2350);
DISPLAY 0.617021 (-4000 2350);
PAINT SKYBLUE (-4000 2350);
FORCEPROP 2 LAST CDS_LIB mstr_discrete
J 0
(-4250 2500);
PAINT ORANGE (-4250 2500);
DISPLAY INVISIBLE (-4250 2500);
FORCEPROP 2 LAST SEC 1
J 0
(-4300 2700);
DISPLAY 0.680851 (-4300 2700);
PAINT MONO (-4300 2700);
DISPLAY INVISIBLE (-4300 2700);
FORCEPROP 2 LAST SEC_TYPE 0402
J 0
(-4300 2700);
DISPLAY 1.021277 (-4300 2700);
PAINT ORANGE (-4300 2700);
DISPLAY INVISIBLE (-4300 2700);
FORCEPROP 1 LAST PATH I115
J 0
(-4300 2650);
DISPLAY 0.978723 (-4300 2650);
PAINT WHITE (-4300 2650);
DISPLAY INVISIBLE (-4300 2650);
FORCEPROP 0 LAST ROOM M_2
J 0
(-4300 2700);
DISPLAY 1.021277 (-4300 2700);
PAINT ORANGE (-4300 2700);
DISPLAY INVISIBLE (-4300 2700);
FORCEPROP 0 LAST BOM_COST ST_FLASH
J 0
(-4300 2800);
DISPLAY 1.021277 (-4300 2800);
PAINT ORANGE (-4300 2800);
DISPLAY INVISIBLE (-4300 2800);
FORCEADD OFFPAGE..2
(-3400 2500);
FORCEPROP 2 LAST $XR0 120 
J 0
(-3181 2500);
DISPLAY 0.638298 (-3181 2500);
PAINT MONO (-3181 2500);
FORCEPROP 1 LAST OFFPAGE TRUE
J 0
(-3075 2375);
DISPLAY 0.872340 (-3075 2375);
PAINT GREEN (-3075 2375);
DISPLAY INVISIBLE (-3075 2375);
FORCEPROP 2 LAST PATH I116
J 0
(-3225 2575);
DISPLAY 1.021277 (-3225 2575);
PAINT ORANGE (-3225 2575);
DISPLAY INVISIBLE (-3225 2575);
FORCEPROP 2 LAST CDS_LIB mstr_standard
J 0
(-3400 2500);
PAINT ORANGE (-3400 2500);
DISPLAY INVISIBLE (-3400 2500);
FORCEPROP 1 LAST COMMENT_BODY TRUE
J 0
(-3445 2405);
DISPLAY 0.872340 (-3445 2405);
PAINT GREEN (-3445 2405);
DISPLAY INVISIBLE (-3445 2405);
FORCEADD CAP_A..1
(-4500 1975);
FORCEPROP 1 LAST PACK_TYPE 0402V
J 0
(-4450 1775);
DISPLAY 0.617021 (-4450 1775);
PAINT SKYBLUE (-4450 1775);
FORCEPROP 1 LASTPIN (-4500 1875) $PN 2
J 0
(-4490 1855);
DISPLAY 0.617021 (-4490 1855);
PAINT ORANGE (-4490 1855);
FORCEPROP 1 LAST MATERIAL X7R
J 0
(-4450 1875);
DISPLAY 0.617021 (-4450 1875);
PAINT SKYBLUE (-4450 1875);
FORCEPROP 1 LAST TOLERANCE 10%
J 0
(-4450 1925);
DISPLAY 0.617021 (-4450 1925);
PAINT SKYBLUE (-4450 1925);
FORCEPROP 1 LAST VOLTAGE 16V
J 0
(-4450 1975);
DISPLAY 0.617021 (-4450 1975);
PAINT SKYBLUE (-4450 1975);
FORCEPROP 1 LAST PART_NUMBER A36096-030
J 0
(-4450 1825);
DISPLAY 0.617021 (-4450 1825);
PAINT BLUE (-4450 1825);
FORCEPROP 1 LAST LOCATION C2P9
J 0
(-4450 2075);
DISPLAY 0.617021 (-4450 2075);
PAINT AQUA (-4450 2075);
FORCEPROP 1 LASTPIN (-4500 2075) $PN 1
J 0
(-4490 2055);
DISPLAY 0.617021 (-4490 2055);
PAINT ORANGE (-4490 2055);
FORCEPROP 1 LAST VALUE 0.1UF
J 0
(-4450 2025);
DISPLAY 0.617021 (-4450 2025);
PAINT SKYBLUE (-4450 2025);
FORCEPROP 0 LAST BOM_COST SD_FLASH
J 0
(-4450 2275);
DISPLAY 1.021277 (-4450 2275);
PAINT ORANGE (-4450 2275);
DISPLAY INVISIBLE (-4450 2275);
FORCEPROP 1 LAST PATH I117
J 0
(-4450 2125);
DISPLAY 0.978723 (-4450 2125);
PAINT WHITE (-4450 2125);
DISPLAY INVISIBLE (-4450 2125);
FORCEPROP 0 LAST ROOM M_2
J 0
(-4450 2175);
DISPLAY 1.021277 (-4450 2175);
PAINT ORANGE (-4450 2175);
DISPLAY INVISIBLE (-4450 2175);
FORCEPROP 2 LAST CDS_SEC 1
J 0
(-4450 2125);
PAINT ORANGE (-4450 2125);
DISPLAY INVISIBLE (-4450 2125);
FORCEPROP 2 LAST SEC 1
J 0
(-4450 2175);
DISPLAY 0.680851 (-4450 2175);
PAINT MONO (-4450 2175);
DISPLAY INVISIBLE (-4450 2175);
FORCEPROP 2 LAST SEC_TYPE 0402V
J 0
(-4450 2175);
DISPLAY 1.021277 (-4450 2175);
PAINT ORANGE (-4450 2175);
DISPLAY INVISIBLE (-4450 2175);
FORCEPROP 2 LAST CDS_LIB dev_discrete
J 0
(-4500 1975);
PAINT ORANGE (-4500 1975);
DISPLAY INVISIBLE (-4500 1975);
FORCEADD P3V3_STBY..1
(-4500 2200);
FORCEPROP 3 LASTPIN (-4500 2150) SIG_NAME P3V3_STBY\g
J 0
(-4490 2160);
DISPLAY 0.659574 (-4490 2160);
PAINT MONO (-4490 2160);
DISPLAY INVISIBLE (-4490 2160);
FORCEPROP 1 LAST SIZE 1B
J 0
(-4455 2222);
DISPLAY 0.340426 (-4455 2222);
PAINT GREEN (-4455 2222);
DISPLAY INVISIBLE (-4455 2222);
FORCEPROP 1 LAST PATH I118
J 0
(-4455 2202);
DISPLAY 0.340426 (-4455 2202);
PAINT GREEN (-4455 2202);
DISPLAY INVISIBLE (-4455 2202);
FORCEPROP 1 LAST BODY_TYPE PLUMBING
J 0
(-4545 2157);
DISPLAY 0.340426 (-4545 2157);
PAINT GREEN (-4545 2157);
DISPLAY INVISIBLE (-4545 2157);
FORCEPROP 2 LAST CDS_LIB mstr_symbols
J 0
(-4500 2200);
PAINT ORANGE (-4500 2200);
DISPLAY INVISIBLE (-4500 2200);
FORCEPROP 1 LAST VOLTAGE 3.3V
J 0
(-4545 2157);
DISPLAY 0.340426 (-4545 2157);
PAINT SKYBLUE (-4545 2157);
DISPLAY INVISIBLE (-4545 2157);
FORCEPROP 1 LAST HDL_POWER P3V3_STBY
J 0
(-4800 2075);
DISPLAY 0.872340 (-4800 2075);
PAINT ORANGE (-4800 2075);
DISPLAY INVISIBLE (-4800 2075);
FORCEADD GND..1
(-4500 1750);
FORCEPROP 3 LASTPIN (-4500 1800) SIG_NAME GND\g
J 0
(-4490 1810);
DISPLAY 0.659574 (-4490 1810);
PAINT MONO (-4490 1810);
DISPLAY INVISIBLE (-4490 1810);
FORCEPROP 1 LAST HDL_POWER GND
J 0
(-4500 1900);
DISPLAY 0.872340 (-4500 1900);
PAINT GREEN (-4500 1900);
DISPLAY INVISIBLE (-4500 1900);
FORCEPROP 2 LAST CDS_LIB mstr_symbols
J 0
(-4500 1750);
PAINT ORANGE (-4500 1750);
DISPLAY INVISIBLE (-4500 1750);
FORCEPROP 1 LAST VOLTAGE 0.0V
J 0
(-4545 1707);
DISPLAY 0.340426 (-4545 1707);
PAINT SKYBLUE (-4545 1707);
DISPLAY INVISIBLE (-4545 1707);
FORCEPROP 1 LAST SIZE 1B
J 0
(-4425 1700);
DISPLAY 0.872340 (-4425 1700);
PAINT AQUA (-4425 1700);
DISPLAY INVISIBLE (-4425 1700);
FORCEPROP 1 LAST BODY_TYPE PLUMBING
J 0
(-4545 1707);
DISPLAY 0.340426 (-4545 1707);
PAINT GREEN (-4545 1707);
DISPLAY INVISIBLE (-4545 1707);
FORCEPROP 1 LAST PATH I119
J 0
(-4425 1750);
DISPLAY 0.872340 (-4425 1750);
PAINT AQUA (-4425 1750);
DISPLAY INVISIBLE (-4425 1750);
FORCEADD CAP_A..1
(-4250 4575);
FORCEPROP 1 LASTPIN (-4250 4675) $PN 1
J 0
(-4240 4655);
DISPLAY 0.617021 (-4240 4655);
PAINT ORANGE (-4240 4655);
FORCEPROP 1 LASTPIN (-4250 4475) $PN 2
J 0
(-4240 4455);
DISPLAY 0.617021 (-4240 4455);
PAINT ORANGE (-4240 4455);
FORCEPROP 1 LAST MATERIAL X7R
J 0
(-4200 4475);
DISPLAY 0.617021 (-4200 4475);
PAINT SKYBLUE (-4200 4475);
FORCEPROP 1 LAST VOLTAGE 16V
J 0
(-4200 4575);
DISPLAY 0.617021 (-4200 4575);
PAINT SKYBLUE (-4200 4575);
FORCEPROP 1 LAST PACK_TYPE 0402V
J 0
(-4200 4375);
DISPLAY 0.617021 (-4200 4375);
PAINT SKYBLUE (-4200 4375);
FORCEPROP 1 LAST TOLERANCE 10%
J 0
(-4200 4525);
DISPLAY 0.617021 (-4200 4525);
PAINT SKYBLUE (-4200 4525);
FORCEPROP 1 LAST VALUE 0.1UF
J 0
(-4200 4625);
DISPLAY 0.617021 (-4200 4625);
PAINT SKYBLUE (-4200 4625);
FORCEPROP 1 LAST LOCATION C2T29
J 0
(-4200 4675);
DISPLAY 0.617021 (-4200 4675);
PAINT AQUA (-4200 4675);
FORCEPROP 1 LAST PART_NUMBER A36096-030
J 0
(-4200 4425);
DISPLAY 0.617021 (-4200 4425);
PAINT BLUE (-4200 4425);
FORCEPROP 2 LAST CDS_LIB dev_discrete
J 0
(-4250 4575);
PAINT ORANGE (-4250 4575);
DISPLAY INVISIBLE (-4250 4575);
FORCEPROP 2 LAST CDS_LOCATION C2T29
J 0
(-4200 4675);
DISPLAY 0.617021 (-4200 4675);
PAINT AQUA (-4200 4675);
DISPLAY INVISIBLE (-4200 4675);
FORCEPROP 2 LAST SEC 1
J 0
(-4200 4775);
DISPLAY 0.680851 (-4200 4775);
PAINT MONO (-4200 4775);
DISPLAY INVISIBLE (-4200 4775);
FORCEPROP 2 LAST CDS_SEC 1
J 0
(-4200 4725);
PAINT ORANGE (-4200 4725);
DISPLAY INVISIBLE (-4200 4725);
FORCEPROP 1 LAST PATH I120
J 0
(-4200 4725);
DISPLAY 0.978723 (-4200 4725);
PAINT WHITE (-4200 4725);
DISPLAY INVISIBLE (-4200 4725);
FORCEPROP 0 LAST ROOM M_2
J 0
(-4200 4775);
DISPLAY 1.021277 (-4200 4775);
PAINT ORANGE (-4200 4775);
DISPLAY INVISIBLE (-4200 4775);
FORCEPROP 2 LAST SEC_TYPE 0402V
J 0
(-4200 4775);
DISPLAY 1.021277 (-4200 4775);
PAINT ORANGE (-4200 4775);
DISPLAY INVISIBLE (-4200 4775);
FORCEPROP 0 LAST BOM_COST SD_FLASH
J 0
(-4200 4875);
DISPLAY 1.021277 (-4200 4875);
PAINT ORANGE (-4200 4875);
DISPLAY INVISIBLE (-4200 4875);
FORCEADD GND..1
(-4250 4350);
FORCEPROP 3 LASTPIN (-4250 4400) SIG_NAME GND\g
J 0
(-4240 4410);
DISPLAY 0.659574 (-4240 4410);
PAINT MONO (-4240 4410);
DISPLAY INVISIBLE (-4240 4410);
FORCEPROP 1 LAST BODY_TYPE PLUMBING
J 0
(-4295 4307);
DISPLAY 0.340426 (-4295 4307);
PAINT GREEN (-4295 4307);
DISPLAY INVISIBLE (-4295 4307);
FORCEPROP 2 LAST CDS_LIB mstr_symbols
J 0
(-4250 4350);
PAINT MONO (-4250 4350);
DISPLAY INVISIBLE (-4250 4350);
FORCEPROP 1 LAST VOLTAGE 0.0V
J 0
(-4295 4307);
DISPLAY 0.340426 (-4295 4307);
PAINT SKYBLUE (-4295 4307);
DISPLAY INVISIBLE (-4295 4307);
FORCEPROP 1 LAST HDL_POWER GND
J 0
(-4250 4500);
DISPLAY 0.872340 (-4250 4500);
PAINT GREEN (-4250 4500);
DISPLAY INVISIBLE (-4250 4500);
FORCEPROP 1 LAST SIZE 1B
J 0
(-4175 4300);
DISPLAY 0.872340 (-4175 4300);
PAINT AQUA (-4175 4300);
DISPLAY INVISIBLE (-4175 4300);
FORCEPROP 1 LAST PATH I122
J 0
(-4175 4350);
DISPLAY 0.872340 (-4175 4350);
PAINT AQUA (-4175 4350);
DISPLAY INVISIBLE (-4175 4350);
FORCEADD CAP_A..1
(-4000 4575);
FORCEPROP 1 LAST VALUE 0.1UF
J 0
(-3950 4625);
DISPLAY 0.617021 (-3950 4625);
PAINT SKYBLUE (-3950 4625);
FORCEPROP 1 LAST LOCATION C2T26
J 0
(-3950 4675);
DISPLAY 0.617021 (-3950 4675);
PAINT AQUA (-3950 4675);
FORCEPROP 1 LASTPIN (-4000 4475) $PN 2
J 0
(-3990 4455);
DISPLAY 0.617021 (-3990 4455);
PAINT ORANGE (-3990 4455);
FORCEPROP 1 LASTPIN (-4000 4675) $PN 1
J 0
(-3990 4655);
DISPLAY 0.617021 (-3990 4655);
PAINT ORANGE (-3990 4655);
FORCEPROP 1 LAST MATERIAL X7R
J 0
(-3950 4475);
DISPLAY 0.617021 (-3950 4475);
PAINT SKYBLUE (-3950 4475);
FORCEPROP 1 LAST VOLTAGE 16V
J 0
(-3950 4575);
DISPLAY 0.617021 (-3950 4575);
PAINT SKYBLUE (-3950 4575);
FORCEPROP 1 LAST PACK_TYPE 0402V
J 0
(-3950 4375);
DISPLAY 0.617021 (-3950 4375);
PAINT SKYBLUE (-3950 4375);
FORCEPROP 1 LAST TOLERANCE 10%
J 0
(-3950 4525);
DISPLAY 0.617021 (-3950 4525);
PAINT SKYBLUE (-3950 4525);
FORCEPROP 1 LAST PART_NUMBER A36096-030
J 0
(-3950 4425);
DISPLAY 0.617021 (-3950 4425);
PAINT BLUE (-3950 4425);
FORCEPROP 2 LAST CDS_LIB dev_discrete
J 0
(-4000 4575);
PAINT ORANGE (-4000 4575);
DISPLAY INVISIBLE (-4000 4575);
FORCEPROP 2 LAST CDS_LOCATION C2T26
J 0
(-3950 4675);
DISPLAY 0.617021 (-3950 4675);
PAINT AQUA (-3950 4675);
DISPLAY INVISIBLE (-3950 4675);
FORCEPROP 1 LAST PATH I123
J 0
(-3950 4725);
DISPLAY 0.978723 (-3950 4725);
PAINT WHITE (-3950 4725);
DISPLAY INVISIBLE (-3950 4725);
FORCEPROP 0 LAST ROOM M_2
J 0
(-3950 4775);
DISPLAY 1.021277 (-3950 4775);
PAINT ORANGE (-3950 4775);
DISPLAY INVISIBLE (-3950 4775);
FORCEPROP 0 LAST BOM_COST SD_FLASH
J 0
(-3950 4875);
DISPLAY 1.021277 (-3950 4875);
PAINT ORANGE (-3950 4875);
DISPLAY INVISIBLE (-3950 4875);
FORCEPROP 2 LAST CDS_SEC 1
J 0
(-3950 4725);
PAINT ORANGE (-3950 4725);
DISPLAY INVISIBLE (-3950 4725);
FORCEPROP 2 LAST SEC 1
J 0
(-3950 4775);
DISPLAY 0.680851 (-3950 4775);
PAINT MONO (-3950 4775);
DISPLAY INVISIBLE (-3950 4775);
FORCEPROP 2 LAST SEC_TYPE 0402V
J 0
(-3950 4775);
DISPLAY 1.021277 (-3950 4775);
PAINT ORANGE (-3950 4775);
DISPLAY INVISIBLE (-3950 4775);
FORCEADD CAP_A..1
(-3750 4575);
FORCEPROP 1 LAST PART_NUMBER A36096-030
J 0
(-3700 4425);
DISPLAY 0.617021 (-3700 4425);
PAINT BLUE (-3700 4425);
FORCEPROP 1 LASTPIN (-3750 4675) $PN 1
J 0
(-3740 4655);
DISPLAY 0.617021 (-3740 4655);
PAINT ORANGE (-3740 4655);
FORCEPROP 1 LASTPIN (-3750 4475) $PN 2
J 0
(-3740 4455);
DISPLAY 0.617021 (-3740 4455);
PAINT ORANGE (-3740 4455);
FORCEPROP 1 LAST VALUE 0.1UF
J 0
(-3700 4625);
DISPLAY 0.617021 (-3700 4625);
PAINT SKYBLUE (-3700 4625);
FORCEPROP 1 LAST TOLERANCE 10%
J 0
(-3700 4525);
DISPLAY 0.617021 (-3700 4525);
PAINT SKYBLUE (-3700 4525);
FORCEPROP 1 LAST PACK_TYPE 0402V
J 0
(-3700 4375);
DISPLAY 0.617021 (-3700 4375);
PAINT SKYBLUE (-3700 4375);
FORCEPROP 1 LAST VOLTAGE 16V
J 0
(-3700 4575);
DISPLAY 0.617021 (-3700 4575);
PAINT SKYBLUE (-3700 4575);
FORCEPROP 1 LAST LOCATION C2T21
J 0
(-3700 4675);
DISPLAY 0.617021 (-3700 4675);
PAINT AQUA (-3700 4675);
FORCEPROP 1 LAST MATERIAL X7R
J 0
(-3700 4475);
DISPLAY 0.617021 (-3700 4475);
PAINT SKYBLUE (-3700 4475);
FORCEPROP 2 LAST CDS_LIB dev_discrete
J 0
(-3750 4575);
PAINT ORANGE (-3750 4575);
DISPLAY INVISIBLE (-3750 4575);
FORCEPROP 2 LAST CDS_LOCATION C2T21
J 0
(-3700 4675);
DISPLAY 0.617021 (-3700 4675);
PAINT AQUA (-3700 4675);
DISPLAY INVISIBLE (-3700 4675);
FORCEPROP 1 LAST PATH I124
J 0
(-3700 4725);
DISPLAY 0.978723 (-3700 4725);
PAINT WHITE (-3700 4725);
DISPLAY INVISIBLE (-3700 4725);
FORCEPROP 0 LAST ROOM M_2
J 0
(-3700 4775);
DISPLAY 1.021277 (-3700 4775);
PAINT ORANGE (-3700 4775);
DISPLAY INVISIBLE (-3700 4775);
FORCEPROP 0 LAST BOM_COST SD_FLASH
J 0
(-3700 4875);
DISPLAY 1.021277 (-3700 4875);
PAINT ORANGE (-3700 4875);
DISPLAY INVISIBLE (-3700 4875);
FORCEPROP 2 LAST CDS_SEC 1
J 0
(-3700 4725);
PAINT ORANGE (-3700 4725);
DISPLAY INVISIBLE (-3700 4725);
FORCEPROP 2 LAST SEC 1
J 0
(-3700 4775);
DISPLAY 0.680851 (-3700 4775);
PAINT MONO (-3700 4775);
DISPLAY INVISIBLE (-3700 4775);
FORCEPROP 2 LAST SEC_TYPE 0402V
J 0
(-3700 4775);
DISPLAY 1.021277 (-3700 4775);
PAINT ORANGE (-3700 4775);
DISPLAY INVISIBLE (-3700 4775);
FORCEADD P3V3..1
(-4250 4800);
FORCEPROP 3 LASTPIN (-4250 4750) SIG_NAME P3V3\g
J 0
(-4240 4760);
DISPLAY 0.659574 (-4240 4760);
PAINT MONO (-4240 4760);
DISPLAY INVISIBLE (-4240 4760);
FORCEPROP 1 LAST HDL_POWER P3V3
J 0
(-4575 4675);
DISPLAY 0.872340 (-4575 4675);
PAINT ORANGE (-4575 4675);
DISPLAY INVISIBLE (-4575 4675);
FORCEPROP 1 LAST BODY_TYPE PLUMBING
J 0
(-4295 4757);
DISPLAY 0.340426 (-4295 4757);
PAINT GREEN (-4295 4757);
DISPLAY INVISIBLE (-4295 4757);
FORCEPROP 1 LAST VOLTAGE 3.3V
J 0
(-4295 4757);
DISPLAY 0.340426 (-4295 4757);
PAINT SKYBLUE (-4295 4757);
DISPLAY INVISIBLE (-4295 4757);
FORCEPROP 2 LAST CDS_LIB mstr_symbols
J 0
(-4250 4800);
PAINT MONO (-4250 4800);
DISPLAY INVISIBLE (-4250 4800);
FORCEPROP 1 LAST PATH I125
J 0
(-4205 4802);
DISPLAY 0.340426 (-4205 4802);
PAINT GREEN (-4205 4802);
DISPLAY INVISIBLE (-4205 4802);
FORCEPROP 1 LAST SIZE 1B
J 0
(-4205 4822);
DISPLAY 0.340426 (-4205 4822);
PAINT GREEN (-4205 4822);
DISPLAY INVISIBLE (-4205 4822);
FORCEADD CAP_A..1
(-2425 4575);
FORCEPROP 1 LAST PART_NUMBER A36096-030
J 0
(-2375 4425);
DISPLAY 0.617021 (-2375 4425);
PAINT BLUE (-2375 4425);
FORCEPROP 1 LAST PACK_TYPE 0402V
J 0
(-2375 4375);
DISPLAY 0.617021 (-2375 4375);
PAINT SKYBLUE (-2375 4375);
FORCEPROP 1 LAST MATERIAL X7R
J 0
(-2375 4475);
DISPLAY 0.617021 (-2375 4475);
PAINT SKYBLUE (-2375 4475);
FORCEPROP 1 LASTPIN (-2425 4475) $PN 2
J 0
(-2415 4455);
DISPLAY 0.617021 (-2415 4455);
PAINT ORANGE (-2415 4455);
FORCEPROP 1 LASTPIN (-2425 4675) $PN 1
J 0
(-2415 4655);
DISPLAY 0.617021 (-2415 4655);
PAINT ORANGE (-2415 4655);
FORCEPROP 1 LAST TOLERANCE 10%
J 0
(-2375 4525);
DISPLAY 0.617021 (-2375 4525);
PAINT SKYBLUE (-2375 4525);
FORCEPROP 1 LAST VALUE 0.1UF
J 0
(-2375 4625);
DISPLAY 0.617021 (-2375 4625);
PAINT SKYBLUE (-2375 4625);
FORCEPROP 1 LAST VOLTAGE 16V
J 0
(-2375 4575);
DISPLAY 0.617021 (-2375 4575);
PAINT SKYBLUE (-2375 4575);
FORCEPROP 1 LAST LOCATION C2T16
J 0
(-2375 4675);
DISPLAY 0.617021 (-2375 4675);
PAINT AQUA (-2375 4675);
FORCEPROP 2 LAST CDS_LIB dev_discrete
J 0
(-2425 4575);
PAINT ORANGE (-2425 4575);
DISPLAY INVISIBLE (-2425 4575);
FORCEPROP 2 LAST CDS_LOCATION C2T16
J 0
(-2375 4675);
DISPLAY 0.617021 (-2375 4675);
PAINT AQUA (-2375 4675);
DISPLAY INVISIBLE (-2375 4675);
FORCEPROP 1 LAST PATH I126
J 0
(-2375 4725);
DISPLAY 0.978723 (-2375 4725);
PAINT WHITE (-2375 4725);
DISPLAY INVISIBLE (-2375 4725);
FORCEPROP 2 LAST CDS_SEC 1
J 0
(-2375 4725);
PAINT ORANGE (-2375 4725);
DISPLAY INVISIBLE (-2375 4725);
FORCEPROP 2 LAST SEC_TYPE 0402V
J 0
(-2375 4775);
DISPLAY 1.021277 (-2375 4775);
PAINT ORANGE (-2375 4775);
DISPLAY INVISIBLE (-2375 4775);
FORCEPROP 2 LAST SEC 1
J 0
(-2375 4775);
DISPLAY 0.680851 (-2375 4775);
PAINT MONO (-2375 4775);
DISPLAY INVISIBLE (-2375 4775);
FORCEPROP 0 LAST ROOM M_2
J 0
(-2375 4775);
DISPLAY 1.021277 (-2375 4775);
PAINT ORANGE (-2375 4775);
DISPLAY INVISIBLE (-2375 4775);
FORCEPROP 0 LAST BOM_COST SD_FLASH
J 0
(-2375 4875);
DISPLAY 1.021277 (-2375 4875);
PAINT ORANGE (-2375 4875);
DISPLAY INVISIBLE (-2375 4875);
FORCEADD CAP_A..1
(-2675 4575);
FORCEPROP 1 LASTPIN (-2675 4475) $PN 2
J 0
(-2665 4455);
DISPLAY 0.617021 (-2665 4455);
PAINT ORANGE (-2665 4455);
FORCEPROP 1 LASTPIN (-2675 4675) $PN 1
J 0
(-2665 4655);
DISPLAY 0.617021 (-2665 4655);
PAINT ORANGE (-2665 4655);
FORCEPROP 1 LAST MATERIAL X7R
J 0
(-2625 4475);
DISPLAY 0.617021 (-2625 4475);
PAINT SKYBLUE (-2625 4475);
FORCEPROP 1 LAST VOLTAGE 16V
J 0
(-2625 4575);
DISPLAY 0.617021 (-2625 4575);
PAINT SKYBLUE (-2625 4575);
FORCEPROP 1 LAST PACK_TYPE 0402V
J 0
(-2625 4375);
DISPLAY 0.617021 (-2625 4375);
PAINT SKYBLUE (-2625 4375);
FORCEPROP 1 LAST TOLERANCE 10%
J 0
(-2625 4525);
DISPLAY 0.617021 (-2625 4525);
PAINT SKYBLUE (-2625 4525);
FORCEPROP 1 LAST VALUE 0.1UF
J 0
(-2625 4625);
DISPLAY 0.617021 (-2625 4625);
PAINT SKYBLUE (-2625 4625);
FORCEPROP 1 LAST PART_NUMBER A36096-030
J 0
(-2625 4425);
DISPLAY 0.617021 (-2625 4425);
PAINT BLUE (-2625 4425);
FORCEPROP 1 LAST LOCATION C2T15
J 0
(-2625 4675);
DISPLAY 0.617021 (-2625 4675);
PAINT AQUA (-2625 4675);
FORCEPROP 2 LAST CDS_LIB dev_discrete
J 0
(-2675 4575);
PAINT ORANGE (-2675 4575);
DISPLAY INVISIBLE (-2675 4575);
FORCEPROP 2 LAST CDS_LOCATION C2T15
J 0
(-2625 4675);
DISPLAY 0.617021 (-2625 4675);
PAINT AQUA (-2625 4675);
DISPLAY INVISIBLE (-2625 4675);
FORCEPROP 1 LAST PATH I127
J 0
(-2625 4725);
DISPLAY 0.978723 (-2625 4725);
PAINT WHITE (-2625 4725);
DISPLAY INVISIBLE (-2625 4725);
FORCEPROP 2 LAST CDS_SEC 1
J 0
(-2625 4725);
PAINT ORANGE (-2625 4725);
DISPLAY INVISIBLE (-2625 4725);
FORCEPROP 0 LAST ROOM M_2
J 0
(-2625 4775);
DISPLAY 1.021277 (-2625 4775);
PAINT ORANGE (-2625 4775);
DISPLAY INVISIBLE (-2625 4775);
FORCEPROP 0 LAST BOM_COST SD_FLASH
J 0
(-2625 4875);
DISPLAY 1.021277 (-2625 4875);
PAINT ORANGE (-2625 4875);
DISPLAY INVISIBLE (-2625 4875);
FORCEPROP 2 LAST SEC 1
J 0
(-2625 4775);
DISPLAY 0.680851 (-2625 4775);
PAINT MONO (-2625 4775);
DISPLAY INVISIBLE (-2625 4775);
FORCEPROP 2 LAST SEC_TYPE 0402V
J 0
(-2625 4775);
DISPLAY 1.021277 (-2625 4775);
PAINT ORANGE (-2625 4775);
DISPLAY INVISIBLE (-2625 4775);
FORCEADD P3V3..1
(-2925 4800);
FORCEPROP 3 LASTPIN (-2925 4750) SIG_NAME P3V3\g
J 0
(-2915 4760);
DISPLAY 0.659574 (-2915 4760);
PAINT MONO (-2915 4760);
DISPLAY INVISIBLE (-2915 4760);
FORCEPROP 1 LAST HDL_POWER P3V3
J 0
(-3250 4675);
DISPLAY 0.872340 (-3250 4675);
PAINT ORANGE (-3250 4675);
DISPLAY INVISIBLE (-3250 4675);
FORCEPROP 1 LAST BODY_TYPE PLUMBING
J 0
(-2970 4757);
DISPLAY 0.340426 (-2970 4757);
PAINT GREEN (-2970 4757);
DISPLAY INVISIBLE (-2970 4757);
FORCEPROP 1 LAST VOLTAGE 3.3V
J 0
(-2970 4757);
DISPLAY 0.340426 (-2970 4757);
PAINT SKYBLUE (-2970 4757);
DISPLAY INVISIBLE (-2970 4757);
FORCEPROP 1 LAST PATH I128
J 0
(-2880 4802);
DISPLAY 0.340426 (-2880 4802);
PAINT GREEN (-2880 4802);
DISPLAY INVISIBLE (-2880 4802);
FORCEPROP 1 LAST SIZE 1B
J 0
(-2880 4822);
DISPLAY 0.340426 (-2880 4822);
PAINT GREEN (-2880 4822);
DISPLAY INVISIBLE (-2880 4822);
FORCEPROP 2 LAST CDS_LIB mstr_symbols
J 0
(-2925 4800);
PAINT MONO (-2925 4800);
DISPLAY INVISIBLE (-2925 4800);
FORCEADD CAP_A..1
(-2925 4575);
FORCEPROP 1 LAST PACK_TYPE 0402V
J 0
(-2875 4375);
DISPLAY 0.617021 (-2875 4375);
PAINT SKYBLUE (-2875 4375);
FORCEPROP 1 LASTPIN (-2925 4475) $PN 2
J 0
(-2915 4455);
DISPLAY 0.617021 (-2915 4455);
PAINT ORANGE (-2915 4455);
FORCEPROP 1 LAST MATERIAL X7R
J 0
(-2875 4475);
DISPLAY 0.617021 (-2875 4475);
PAINT SKYBLUE (-2875 4475);
FORCEPROP 1 LASTPIN (-2925 4675) $PN 1
J 0
(-2915 4655);
DISPLAY 0.617021 (-2915 4655);
PAINT ORANGE (-2915 4655);
FORCEPROP 1 LAST VOLTAGE 16V
J 0
(-2875 4575);
DISPLAY 0.617021 (-2875 4575);
PAINT SKYBLUE (-2875 4575);
FORCEPROP 1 LAST TOLERANCE 10%
J 0
(-2875 4525);
DISPLAY 0.617021 (-2875 4525);
PAINT SKYBLUE (-2875 4525);
FORCEPROP 1 LAST VALUE 0.1UF
J 0
(-2875 4625);
DISPLAY 0.617021 (-2875 4625);
PAINT SKYBLUE (-2875 4625);
FORCEPROP 1 LAST LOCATION C2T24
J 0
(-2875 4675);
DISPLAY 0.617021 (-2875 4675);
PAINT AQUA (-2875 4675);
FORCEPROP 1 LAST PART_NUMBER A36096-030
J 0
(-2875 4425);
DISPLAY 0.617021 (-2875 4425);
PAINT BLUE (-2875 4425);
FORCEPROP 2 LAST CDS_LIB dev_discrete
J 0
(-2925 4575);
PAINT ORANGE (-2925 4575);
DISPLAY INVISIBLE (-2925 4575);
FORCEPROP 2 LAST CDS_LOCATION C2T24
J 0
(-2875 4675);
DISPLAY 0.617021 (-2875 4675);
PAINT AQUA (-2875 4675);
DISPLAY INVISIBLE (-2875 4675);
FORCEPROP 2 LAST CDS_SEC 1
J 0
(-2875 4725);
PAINT ORANGE (-2875 4725);
DISPLAY INVISIBLE (-2875 4725);
FORCEPROP 1 LAST PATH I129
J 0
(-2875 4725);
DISPLAY 0.978723 (-2875 4725);
PAINT WHITE (-2875 4725);
DISPLAY INVISIBLE (-2875 4725);
FORCEPROP 0 LAST BOM_COST SD_FLASH
J 0
(-2875 4875);
DISPLAY 1.021277 (-2875 4875);
PAINT ORANGE (-2875 4875);
DISPLAY INVISIBLE (-2875 4875);
FORCEPROP 0 LAST ROOM M_2
J 0
(-2875 4775);
DISPLAY 1.021277 (-2875 4775);
PAINT ORANGE (-2875 4775);
DISPLAY INVISIBLE (-2875 4775);
FORCEPROP 2 LAST SEC 1
J 0
(-2875 4775);
DISPLAY 0.680851 (-2875 4775);
PAINT MONO (-2875 4775);
DISPLAY INVISIBLE (-2875 4775);
FORCEPROP 2 LAST SEC_TYPE 0402V
J 0
(-2875 4775);
DISPLAY 1.021277 (-2875 4775);
PAINT ORANGE (-2875 4775);
DISPLAY INVISIBLE (-2875 4775);
FORCEADD GND..1
(-2925 4350);
FORCEPROP 3 LASTPIN (-2925 4400) SIG_NAME GND\g
J 0
(-2915 4410);
DISPLAY 0.659574 (-2915 4410);
PAINT MONO (-2915 4410);
DISPLAY INVISIBLE (-2915 4410);
FORCEPROP 1 LAST VOLTAGE 0.0V
J 0
(-2970 4307);
DISPLAY 0.340426 (-2970 4307);
PAINT SKYBLUE (-2970 4307);
DISPLAY INVISIBLE (-2970 4307);
FORCEPROP 1 LAST BODY_TYPE PLUMBING
J 0
(-2970 4307);
DISPLAY 0.340426 (-2970 4307);
PAINT GREEN (-2970 4307);
DISPLAY INVISIBLE (-2970 4307);
FORCEPROP 2 LAST CDS_LIB mstr_symbols
J 0
(-2925 4350);
PAINT MONO (-2925 4350);
DISPLAY INVISIBLE (-2925 4350);
FORCEPROP 1 LAST SIZE 1B
J 0
(-2850 4300);
DISPLAY 0.872340 (-2850 4300);
PAINT AQUA (-2850 4300);
DISPLAY INVISIBLE (-2850 4300);
FORCEPROP 1 LAST PATH I130
J 0
(-2850 4350);
DISPLAY 0.872340 (-2850 4350);
PAINT AQUA (-2850 4350);
DISPLAY INVISIBLE (-2850 4350);
FORCEPROP 1 LAST HDL_POWER GND
J 0
(-2925 4500);
DISPLAY 0.872340 (-2925 4500);
PAINT GREEN (-2925 4500);
DISPLAY INVISIBLE (-2925 4500);
FORCEADD CAP_A..1
(-950 4575);
FORCEPROP 1 LAST VALUE 0.1UF
J 0
(-900 4625);
DISPLAY 0.617021 (-900 4625);
PAINT SKYBLUE (-900 4625);
FORCEPROP 1 LAST TOLERANCE 10%
J 0
(-900 4525);
DISPLAY 0.617021 (-900 4525);
PAINT SKYBLUE (-900 4525);
FORCEPROP 1 LAST PACK_TYPE 0402V
J 0
(-900 4375);
DISPLAY 0.617021 (-900 4375);
PAINT SKYBLUE (-900 4375);
FORCEPROP 1 LAST VOLTAGE 16V
J 0
(-900 4575);
DISPLAY 0.617021 (-900 4575);
PAINT SKYBLUE (-900 4575);
FORCEPROP 1 LASTPIN (-950 4675) $PN 1
J 0
(-940 4655);
DISPLAY 0.617021 (-940 4655);
PAINT ORANGE (-940 4655);
FORCEPROP 1 LASTPIN (-950 4475) $PN 2
J 0
(-940 4455);
DISPLAY 0.617021 (-940 4455);
PAINT ORANGE (-940 4455);
FORCEPROP 1 LAST MATERIAL X7R
J 0
(-900 4475);
DISPLAY 0.617021 (-900 4475);
PAINT SKYBLUE (-900 4475);
FORCEPROP 1 LAST LOCATION C2T2
J 0
(-900 4675);
DISPLAY 0.617021 (-900 4675);
PAINT AQUA (-900 4675);
FORCEPROP 1 LAST PART_NUMBER A36096-030
J 0
(-900 4425);
DISPLAY 0.617021 (-900 4425);
PAINT BLUE (-900 4425);
FORCEPROP 0 LAST BOM_COST SD_FLASH
J 0
(-900 4875);
DISPLAY 1.021277 (-900 4875);
PAINT ORANGE (-900 4875);
DISPLAY INVISIBLE (-900 4875);
FORCEPROP 2 LAST CDS_LOCATION C2T2
J 0
(-900 4675);
DISPLAY 0.617021 (-900 4675);
PAINT AQUA (-900 4675);
DISPLAY INVISIBLE (-900 4675);
FORCEPROP 2 LAST CDS_SEC 1
J 0
(-900 4725);
PAINT ORANGE (-900 4725);
DISPLAY INVISIBLE (-900 4725);
FORCEPROP 2 LAST SEC 1
J 0
(-900 4775);
DISPLAY 0.680851 (-900 4775);
PAINT MONO (-900 4775);
DISPLAY INVISIBLE (-900 4775);
FORCEPROP 2 LAST SEC_TYPE 0402V
J 0
(-900 4775);
DISPLAY 1.021277 (-900 4775);
PAINT ORANGE (-900 4775);
DISPLAY INVISIBLE (-900 4775);
FORCEPROP 1 LAST PATH I131
J 0
(-900 4725);
DISPLAY 0.978723 (-900 4725);
PAINT WHITE (-900 4725);
DISPLAY INVISIBLE (-900 4725);
FORCEPROP 0 LAST ROOM M_2
J 0
(-900 4775);
DISPLAY 1.021277 (-900 4775);
PAINT ORANGE (-900 4775);
DISPLAY INVISIBLE (-900 4775);
FORCEPROP 2 LAST CDS_LIB dev_discrete
J 0
(-950 4575);
PAINT ORANGE (-950 4575);
DISPLAY INVISIBLE (-950 4575);
FORCEADD CAP_A..1
(-1200 4575);
FORCEPROP 1 LAST VALUE 0.1UF
J 0
(-1150 4625);
DISPLAY 0.617021 (-1150 4625);
PAINT SKYBLUE (-1150 4625);
FORCEPROP 1 LAST PART_NUMBER A36096-030
J 0
(-1150 4425);
DISPLAY 0.617021 (-1150 4425);
PAINT BLUE (-1150 4425);
FORCEPROP 1 LAST TOLERANCE 10%
J 0
(-1150 4525);
DISPLAY 0.617021 (-1150 4525);
PAINT SKYBLUE (-1150 4525);
FORCEPROP 1 LAST PACK_TYPE 0402V
J 0
(-1150 4375);
DISPLAY 0.617021 (-1150 4375);
PAINT SKYBLUE (-1150 4375);
FORCEPROP 1 LAST VOLTAGE 16V
J 0
(-1150 4575);
DISPLAY 0.617021 (-1150 4575);
PAINT SKYBLUE (-1150 4575);
FORCEPROP 1 LASTPIN (-1200 4675) $PN 1
J 0
(-1190 4655);
DISPLAY 0.617021 (-1190 4655);
PAINT ORANGE (-1190 4655);
FORCEPROP 1 LASTPIN (-1200 4475) $PN 2
J 0
(-1190 4455);
DISPLAY 0.617021 (-1190 4455);
PAINT ORANGE (-1190 4455);
FORCEPROP 1 LAST MATERIAL X7R
J 0
(-1150 4475);
DISPLAY 0.617021 (-1150 4475);
PAINT SKYBLUE (-1150 4475);
FORCEPROP 1 LAST LOCATION C2T4
J 0
(-1150 4675);
DISPLAY 0.617021 (-1150 4675);
PAINT AQUA (-1150 4675);
FORCEPROP 0 LAST BOM_COST SD_FLASH
J 0
(-1150 4875);
DISPLAY 1.021277 (-1150 4875);
PAINT ORANGE (-1150 4875);
DISPLAY INVISIBLE (-1150 4875);
FORCEPROP 2 LAST SEC_TYPE 0402V
J 0
(-1150 4775);
DISPLAY 1.021277 (-1150 4775);
PAINT ORANGE (-1150 4775);
DISPLAY INVISIBLE (-1150 4775);
FORCEPROP 2 LAST SEC 1
J 0
(-1150 4775);
DISPLAY 0.680851 (-1150 4775);
PAINT MONO (-1150 4775);
DISPLAY INVISIBLE (-1150 4775);
FORCEPROP 2 LAST CDS_SEC 1
J 0
(-1150 4725);
PAINT ORANGE (-1150 4725);
DISPLAY INVISIBLE (-1150 4725);
FORCEPROP 0 LAST ROOM M_2
J 0
(-1150 4775);
DISPLAY 1.021277 (-1150 4775);
PAINT ORANGE (-1150 4775);
DISPLAY INVISIBLE (-1150 4775);
FORCEPROP 1 LAST PATH I132
J 0
(-1150 4725);
DISPLAY 0.978723 (-1150 4725);
PAINT WHITE (-1150 4725);
DISPLAY INVISIBLE (-1150 4725);
FORCEPROP 2 LAST CDS_LOCATION C2T4
J 0
(-1150 4675);
DISPLAY 0.617021 (-1150 4675);
PAINT AQUA (-1150 4675);
DISPLAY INVISIBLE (-1150 4675);
FORCEPROP 2 LAST CDS_LIB dev_discrete
J 0
(-1200 4575);
PAINT ORANGE (-1200 4575);
DISPLAY INVISIBLE (-1200 4575);
FORCEADD P3V3..1
(-1450 4800);
FORCEPROP 3 LASTPIN (-1450 4750) SIG_NAME P3V3\g
J 0
(-1440 4760);
DISPLAY 0.659574 (-1440 4760);
PAINT MONO (-1440 4760);
DISPLAY INVISIBLE (-1440 4760);
FORCEPROP 1 LAST PATH I133
J 0
(-1405 4802);
DISPLAY 0.340426 (-1405 4802);
PAINT GREEN (-1405 4802);
DISPLAY INVISIBLE (-1405 4802);
FORCEPROP 1 LAST SIZE 1B
J 0
(-1405 4822);
DISPLAY 0.340426 (-1405 4822);
PAINT GREEN (-1405 4822);
DISPLAY INVISIBLE (-1405 4822);
FORCEPROP 1 LAST BODY_TYPE PLUMBING
J 0
(-1495 4757);
DISPLAY 0.340426 (-1495 4757);
PAINT GREEN (-1495 4757);
DISPLAY INVISIBLE (-1495 4757);
FORCEPROP 2 LAST CDS_LIB mstr_symbols
J 0
(-1450 4800);
PAINT MONO (-1450 4800);
DISPLAY INVISIBLE (-1450 4800);
FORCEPROP 1 LAST VOLTAGE 3.3V
J 0
(-1495 4757);
DISPLAY 0.340426 (-1495 4757);
PAINT SKYBLUE (-1495 4757);
DISPLAY INVISIBLE (-1495 4757);
FORCEPROP 1 LAST HDL_POWER P3V3
J 0
(-1775 4675);
DISPLAY 0.872340 (-1775 4675);
PAINT ORANGE (-1775 4675);
DISPLAY INVISIBLE (-1775 4675);
FORCEADD GND..1
(-1450 4350);
FORCEPROP 3 LASTPIN (-1450 4400) SIG_NAME GND\g
J 0
(-1440 4410);
DISPLAY 0.659574 (-1440 4410);
PAINT MONO (-1440 4410);
DISPLAY INVISIBLE (-1440 4410);
FORCEPROP 1 LAST PATH I134
J 0
(-1375 4350);
DISPLAY 0.872340 (-1375 4350);
PAINT AQUA (-1375 4350);
DISPLAY INVISIBLE (-1375 4350);
FORCEPROP 1 LAST HDL_POWER GND
J 0
(-1450 4500);
DISPLAY 0.872340 (-1450 4500);
PAINT GREEN (-1450 4500);
DISPLAY INVISIBLE (-1450 4500);
FORCEPROP 2 LAST CDS_LIB mstr_symbols
J 0
(-1450 4350);
PAINT MONO (-1450 4350);
DISPLAY INVISIBLE (-1450 4350);
FORCEPROP 1 LAST SIZE 1B
J 0
(-1375 4300);
DISPLAY 0.872340 (-1375 4300);
PAINT AQUA (-1375 4300);
DISPLAY INVISIBLE (-1375 4300);
FORCEPROP 1 LAST VOLTAGE 0.0V
J 0
(-1495 4307);
DISPLAY 0.340426 (-1495 4307);
PAINT SKYBLUE (-1495 4307);
DISPLAY INVISIBLE (-1495 4307);
FORCEPROP 1 LAST BODY_TYPE PLUMBING
J 0
(-1495 4307);
DISPLAY 0.340426 (-1495 4307);
PAINT GREEN (-1495 4307);
DISPLAY INVISIBLE (-1495 4307);
FORCEADD CAP_A..1
(-1450 4575);
FORCEPROP 1 LAST PACK_TYPE 0402V
J 0
(-1400 4375);
DISPLAY 0.617021 (-1400 4375);
PAINT SKYBLUE (-1400 4375);
FORCEPROP 1 LAST PART_NUMBER A36096-030
J 0
(-1400 4425);
DISPLAY 0.617021 (-1400 4425);
PAINT BLUE (-1400 4425);
FORCEPROP 1 LAST TOLERANCE 10%
J 0
(-1400 4525);
DISPLAY 0.617021 (-1400 4525);
PAINT SKYBLUE (-1400 4525);
FORCEPROP 1 LAST LOCATION C2T5
J 0
(-1400 4675);
DISPLAY 0.617021 (-1400 4675);
PAINT AQUA (-1400 4675);
FORCEPROP 1 LASTPIN (-1450 4675) $PN 1
J 0
(-1440 4655);
DISPLAY 0.617021 (-1440 4655);
PAINT ORANGE (-1440 4655);
FORCEPROP 1 LAST VALUE 0.1UF
J 0
(-1400 4625);
DISPLAY 0.617021 (-1400 4625);
PAINT SKYBLUE (-1400 4625);
FORCEPROP 1 LAST VOLTAGE 16V
J 0
(-1400 4575);
DISPLAY 0.617021 (-1400 4575);
PAINT SKYBLUE (-1400 4575);
FORCEPROP 1 LAST MATERIAL X7R
J 0
(-1400 4475);
DISPLAY 0.617021 (-1400 4475);
PAINT SKYBLUE (-1400 4475);
FORCEPROP 1 LASTPIN (-1450 4475) $PN 2
J 0
(-1440 4455);
DISPLAY 0.617021 (-1440 4455);
PAINT ORANGE (-1440 4455);
FORCEPROP 0 LAST BOM_COST SD_FLASH
J 0
(-1400 4875);
DISPLAY 1.021277 (-1400 4875);
PAINT ORANGE (-1400 4875);
DISPLAY INVISIBLE (-1400 4875);
FORCEPROP 2 LAST SEC_TYPE 0402V
J 0
(-1400 4775);
DISPLAY 1.021277 (-1400 4775);
PAINT ORANGE (-1400 4775);
DISPLAY INVISIBLE (-1400 4775);
FORCEPROP 2 LAST SEC 1
J 0
(-1400 4775);
DISPLAY 0.680851 (-1400 4775);
PAINT MONO (-1400 4775);
DISPLAY INVISIBLE (-1400 4775);
FORCEPROP 2 LAST CDS_SEC 1
J 0
(-1400 4725);
PAINT ORANGE (-1400 4725);
DISPLAY INVISIBLE (-1400 4725);
FORCEPROP 0 LAST ROOM M_2
J 0
(-1400 4775);
DISPLAY 1.021277 (-1400 4775);
PAINT ORANGE (-1400 4775);
DISPLAY INVISIBLE (-1400 4775);
FORCEPROP 1 LAST PATH I135
J 0
(-1400 4725);
DISPLAY 0.978723 (-1400 4725);
PAINT WHITE (-1400 4725);
DISPLAY INVISIBLE (-1400 4725);
FORCEPROP 2 LAST CDS_LOCATION C2T5
J 0
(-1400 4675);
DISPLAY 0.617021 (-1400 4675);
PAINT AQUA (-1400 4675);
DISPLAY INVISIBLE (-1400 4675);
FORCEPROP 2 LAST CDS_LIB dev_discrete
J 0
(-1450 4575);
PAINT ORANGE (-1450 4575);
DISPLAY INVISIBLE (-1450 4575);
FORCEADD RES..2
(-8000 3500);
FORCEPROP 1 LAST PART_NUMBER G21796-016
J 0
(-7960 3375);
DISPLAY 0.617021 (-7960 3375);
PAINT BLUE (-7960 3375);
FORCEPROP 1 LAST MATERIAL CHIP
J 0
(-7960 3425);
DISPLAY 0.617021 (-7960 3425);
PAINT SKYBLUE (-7960 3425);
FORCEPROP 1 LASTPIN (-8000 3400) $PN 2
J 0
(-7995 3410);
DISPLAY 0.617021 (-7995 3410);
PAINT ORANGE (-7995 3410);
FORCEPROP 1 LAST VALUE 10.0K
J 0
(-7955 3575);
DISPLAY 0.617021 (-7955 3575);
PAINT SKYBLUE (-7955 3575);
FORCEPROP 1 LAST LOCATION R8F36
J 0
(-7955 3625);
DISPLAY 0.617021 (-7955 3625);
PAINT AQUA (-7955 3625);
FORCEPROP 1 LASTPIN (-8000 3600) $PN 1
J 0
(-7995 3562);
DISPLAY 0.617021 (-7995 3562);
PAINT ORANGE (-7995 3562);
FORCEPROP 1 LAST TOLERANCE 1%
J 0
(-7955 3525);
DISPLAY 0.617021 (-7955 3525);
PAINT SKYBLUE (-7955 3525);
FORCEPROP 1 LAST WATTAGE 1/16W
J 0
(-7960 3475);
DISPLAY 0.617021 (-7960 3475);
PAINT SKYBLUE (-7960 3475);
FORCEPROP 1 LAST PACK_TYPE 0402
J 0
(-7960 3325);
DISPLAY 0.617021 (-7960 3325);
PAINT SKYBLUE (-7960 3325);
FORCEPROP 0 LAST BOM_COST ST_FLASH
J 0
(-7950 3825);
DISPLAY 1.021277 (-7950 3825);
PAINT ORANGE (-7950 3825);
DISPLAY INVISIBLE (-7950 3825);
FORCEPROP 2 LAST SEC 1
J 0
(-7950 3725);
DISPLAY 0.680851 (-7950 3725);
PAINT MONO (-7950 3725);
DISPLAY INVISIBLE (-7950 3725);
FORCEPROP 2 LAST SEC_TYPE 0402
J 0
(-7950 3725);
DISPLAY 1.021277 (-7950 3725);
PAINT ORANGE (-7950 3725);
DISPLAY INVISIBLE (-7950 3725);
FORCEPROP 1 LAST PATH I136
J 0
(-7950 3675);
DISPLAY 0.978723 (-7950 3675);
PAINT WHITE (-7950 3675);
DISPLAY INVISIBLE (-7950 3675);
FORCEPROP 0 LAST ROOM M_2
J 0
(-7950 3725);
DISPLAY 1.021277 (-7950 3725);
PAINT ORANGE (-7950 3725);
DISPLAY INVISIBLE (-7950 3725);
FORCEPROP 2 LAST CDS_LIB mstr_discrete
J 0
(-8000 3500);
PAINT ORANGE (-8000 3500);
DISPLAY INVISIBLE (-8000 3500);
FORCEADD P3V3..1
(-8000 3700);
FORCEPROP 3 LASTPIN (-8000 3650) SIG_NAME P3V3\g
J 0
(-7990 3660);
DISPLAY 0.659574 (-7990 3660);
PAINT MONO (-7990 3660);
DISPLAY INVISIBLE (-7990 3660);
FORCEPROP 1 LAST SIZE 1B
J 0
(-7955 3722);
DISPLAY 0.340426 (-7955 3722);
PAINT GREEN (-7955 3722);
DISPLAY INVISIBLE (-7955 3722);
FORCEPROP 2 LAST CDS_LIB mstr_symbols
J 0
(-8000 3700);
PAINT ORANGE (-8000 3700);
DISPLAY INVISIBLE (-8000 3700);
FORCEPROP 1 LAST PATH I137
J 0
(-7955 3702);
DISPLAY 0.340426 (-7955 3702);
PAINT GREEN (-7955 3702);
DISPLAY INVISIBLE (-7955 3702);
FORCEPROP 1 LAST VOLTAGE 3.3V
J 0
(-8045 3657);
DISPLAY 0.340426 (-8045 3657);
PAINT SKYBLUE (-8045 3657);
DISPLAY INVISIBLE (-8045 3657);
FORCEPROP 1 LAST BODY_TYPE PLUMBING
J 0
(-8045 3657);
DISPLAY 0.340426 (-8045 3657);
PAINT GREEN (-8045 3657);
DISPLAY INVISIBLE (-8045 3657);
FORCEPROP 1 LAST HDL_POWER P3V3
J 0
(-8325 3575);
DISPLAY 0.872340 (-8325 3575);
PAINT ORANGE (-8325 3575);
DISPLAY INVISIBLE (-8325 3575);
FORCEADD CAP_A..1
R 1
(-2600 2100);
FORCEPROP 0 LAST GROUP M2_SATA
J 0
(-2700 2175);
DISPLAY 0.638298 (-2700 2175);
PAINT BROWN (-2700 2175);
DISPLAY BOTH (-2700 2175);
FORCEPROP 1 LASTPIN (-2500 2100) $PN 2
J 0
(-2530 2110);
DISPLAY 0.787234 (-2530 2110);
PAINT ORANGE (-2530 2110);
FORCEPROP 1 LAST PART_NUMBER A36096-045
J 0
(-2475 2100);
DISPLAY 0.638298 (-2475 2100);
PAINT BLUE (-2475 2100);
FORCEPROP 1 LAST VOLTAGE 25V
J 0
(-2750 2050);
DISPLAY 0.638298 (-2750 2050);
PAINT SKYBLUE (-2750 2050);
FORCEPROP 1 LAST TOLERANCE 10%
J 0
(-2875 2050);
DISPLAY 0.638298 (-2875 2050);
PAINT SKYBLUE (-2875 2050);
FORCEPROP 1 LAST VALUE 0.01UF
J 0
(-3025 2050);
DISPLAY 0.638298 (-3025 2050);
PAINT SKYBLUE (-3025 2050);
FORCEPROP 1 LAST PACK_TYPE 0402V
J 0
(-2475 2050);
DISPLAY 0.638298 (-2475 2050);
PAINT SKYBLUE (-2475 2050);
FORCEPROP 1 LAST MATERIAL X7R
J 0
(-2325 2050);
DISPLAY 0.638298 (-2325 2050);
PAINT SKYBLUE (-2325 2050);
FORCEPROP 1 LASTPIN (-2700 2100) $PN 1
J 0
(-2705 2110);
DISPLAY 0.787234 (-2705 2110);
PAINT ORANGE (-2705 2110);
FORCEPROP 1 LAST LOCATION C8F6
J 0
(-3050 2100);
DISPLAY 0.638298 (-3050 2100);
PAINT SKYBLUE (-3050 2100);
FORCEPROP 2 LAST SEC 1
J 0
(-2700 2200);
DISPLAY 0.680851 (-2700 2200);
PAINT MONO (-2700 2200);
DISPLAY INVISIBLE (-2700 2200);
FORCEPROP 2 LAST SEC_TYPE 0402V
J 0
(-2700 2200);
DISPLAY 1.021277 (-2700 2200);
PAINT ORANGE (-2700 2200);
DISPLAY INVISIBLE (-2700 2200);
FORCEPROP 2 LAST CDS_LIB dev_discrete
R 1
J 0
(-2600 2100);
PAINT MONO (-2600 2100);
DISPLAY INVISIBLE (-2600 2100);
FORCEPROP 1 LAST PATH I138
R 1
J 0
(-2750 2150);
DISPLAY 0.978723 (-2750 2150);
PAINT WHITE (-2750 2150);
DISPLAY INVISIBLE (-2750 2150);
FORCEADD CAP_A..1
R 1
(-2600 1600);
FORCEPROP 1 LASTPIN (-2500 1600) $PN 2
J 0
(-2530 1610);
DISPLAY 0.787234 (-2530 1610);
PAINT ORANGE (-2530 1610);
FORCEPROP 1 LAST VOLTAGE 25V
J 0
(-2750 1550);
DISPLAY 0.638298 (-2750 1550);
PAINT SKYBLUE (-2750 1550);
FORCEPROP 1 LAST LOCATION C8F11
J 0
(-3050 1600);
DISPLAY 0.638298 (-3050 1600);
PAINT SKYBLUE (-3050 1600);
FORCEPROP 1 LAST VALUE 0.01UF
J 0
(-3025 1550);
DISPLAY 0.638298 (-3025 1550);
PAINT SKYBLUE (-3025 1550);
FORCEPROP 1 LASTPIN (-2700 1600) $PN 1
J 0
(-2705 1610);
DISPLAY 0.787234 (-2705 1610);
PAINT ORANGE (-2705 1610);
FORCEPROP 1 LAST TOLERANCE 10%
J 0
(-2875 1550);
DISPLAY 0.638298 (-2875 1550);
PAINT SKYBLUE (-2875 1550);
FORCEPROP 1 LAST PACK_TYPE 0402V
J 0
(-2475 1550);
DISPLAY 0.638298 (-2475 1550);
PAINT SKYBLUE (-2475 1550);
FORCEPROP 1 LAST MATERIAL X7R
J 0
(-2325 1550);
DISPLAY 0.638298 (-2325 1550);
PAINT SKYBLUE (-2325 1550);
FORCEPROP 1 LAST PART_NUMBER A36096-045
J 0
(-2475 1600);
DISPLAY 0.638298 (-2475 1600);
PAINT BLUE (-2475 1600);
FORCEPROP 0 LAST GROUP M2_SATA
J 0
(-2700 1675);
DISPLAY 0.638298 (-2700 1675);
PAINT BROWN (-2700 1675);
DISPLAY BOTH (-2700 1675);
FORCEPROP 2 LAST CDS_LIB dev_discrete
R 1
J 0
(-2600 1600);
PAINT MONO (-2600 1600);
DISPLAY INVISIBLE (-2600 1600);
FORCEPROP 2 LAST SEC_TYPE 0402V
J 0
(-2700 1700);
DISPLAY 1.021277 (-2700 1700);
PAINT ORANGE (-2700 1700);
DISPLAY INVISIBLE (-2700 1700);
FORCEPROP 2 LAST SEC 1
J 0
(-2700 1700);
DISPLAY 0.680851 (-2700 1700);
PAINT MONO (-2700 1700);
DISPLAY INVISIBLE (-2700 1700);
FORCEPROP 1 LAST PATH I139
R 1
J 0
(-2750 1650);
DISPLAY 0.978723 (-2750 1650);
PAINT WHITE (-2750 1650);
DISPLAY INVISIBLE (-2750 1650);
FORCEADD CAP..2
(-2600 1375);
FORCEPROP 1 LAST PACK_TYPE 0402
J 2
(-2125 1375);
DISPLAY 0.617021 (-2125 1375);
PAINT SKYBLUE (-2125 1375);
FORCEPROP 1 LAST VOLTAGE 16V
J 0
(-2350 1375);
DISPLAY 0.617021 (-2350 1375);
PAINT SKYBLUE (-2350 1375);
FORCEPROP 1 LAST PART_NUMBER A36096-155
J 2
(-1850 1375);
DISPLAY 0.617021 (-1850 1375);
PAINT BLUE (-1850 1375);
FORCEPROP 1 LAST VALUE 0.22UF
J 1
(-2875 1375);
DISPLAY 0.617021 (-2875 1375);
PAINT SKYBLUE (-2875 1375);
FORCEPROP 1 LAST MATERIAL X7R
J 0
(-2450 1375);
DISPLAY 0.617021 (-2450 1375);
PAINT SKYBLUE (-2450 1375);
FORCEPROP 1 LASTPIN (-2700 1375) $PN 1
J 0
(-2710 1390);
DISPLAY 0.617021 (-2710 1390);
PAINT ORANGE (-2710 1390);
FORCEPROP 1 LASTPIN (-2500 1375) $PN 2
J 0
(-2515 1390);
DISPLAY 0.617021 (-2515 1390);
PAINT ORANGE (-2515 1390);
FORCEPROP 1 LAST TOLERANCE 10%
J 2
(-2725 1375);
DISPLAY 0.617021 (-2725 1375);
PAINT SKYBLUE (-2725 1375);
FORCEPROP 1 LAST LOCATION C8F12
J 0
(-3100 1375);
DISPLAY 0.617021 (-3100 1375);
PAINT AQUA (-3100 1375);
FORCEPROP 0 LAST GROUP M2_PCIE
J 0
(-2725 1425);
DISPLAY 0.638298 (-2725 1425);
PAINT BROWN (-2725 1425);
DISPLAY BOTH (-2725 1425);
FORCEPROP 2 LAST SEC 1
J 0
(-2600 1625);
DISPLAY 0.680851 (-2600 1625);
PAINT MONO (-2600 1625);
DISPLAY INVISIBLE (-2600 1625);
FORCEPROP 2 LAST SEC_TYPE 0402
J 0
(-2600 1625);
DISPLAY 1.021277 (-2600 1625);
PAINT ORANGE (-2600 1625);
DISPLAY INVISIBLE (-2600 1625);
FORCEPROP 0 LAST BOM_COST ST_FLASH
J 0
(-1850 1475);
DISPLAY 1.021277 (-1850 1475);
PAINT ORANGE (-1850 1475);
DISPLAY INVISIBLE (-1850 1475);
FORCEPROP 0 LAST ROOM M_2
J 0
(-1850 1425);
DISPLAY 1.021277 (-1850 1425);
PAINT ORANGE (-1850 1425);
DISPLAY INVISIBLE (-1850 1425);
FORCEPROP 2 LAST CDS_LIB mstr_discrete
J 0
(-2600 1375);
PAINT ORANGE (-2600 1375);
DISPLAY INVISIBLE (-2600 1375);
FORCEPROP 1 LAST PATH I140
J 0
(-2600 1575);
DISPLAY 0.978723 (-2600 1575);
PAINT WHITE (-2600 1575);
DISPLAY INVISIBLE (-2600 1575);
FORCEPROP 2 LAST CDS_LOCATION C8F12
J 0
(-3100 1375);
DISPLAY 0.617021 (-3100 1375);
PAINT AQUA (-3100 1375);
DISPLAY INVISIBLE (-3100 1375);
FORCEADD CAP_A..1
R 1
(-2600 1175);
FORCEPROP 1 LAST PACK_TYPE 0402V
J 0
(-2475 1125);
DISPLAY 0.638298 (-2475 1125);
PAINT SKYBLUE (-2475 1125);
FORCEPROP 1 LAST TOLERANCE 10%
J 0
(-2875 1125);
DISPLAY 0.638298 (-2875 1125);
PAINT SKYBLUE (-2875 1125);
FORCEPROP 1 LAST VALUE 0.01UF
J 0
(-3025 1125);
DISPLAY 0.638298 (-3025 1125);
PAINT SKYBLUE (-3025 1125);
FORCEPROP 1 LAST PART_NUMBER A36096-045
J 0
(-2475 1175);
DISPLAY 0.638298 (-2475 1175);
PAINT BLUE (-2475 1175);
FORCEPROP 1 LASTPIN (-2700 1175) $PN 1
J 0
(-2705 1185);
DISPLAY 0.787234 (-2705 1185);
PAINT ORANGE (-2705 1185);
FORCEPROP 1 LASTPIN (-2500 1175) $PN 2
J 0
(-2530 1185);
DISPLAY 0.787234 (-2530 1185);
PAINT ORANGE (-2530 1185);
FORCEPROP 1 LAST MATERIAL X7R
J 0
(-2325 1125);
DISPLAY 0.638298 (-2325 1125);
PAINT SKYBLUE (-2325 1125);
FORCEPROP 1 LAST VOLTAGE 25V
J 0
(-2750 1125);
DISPLAY 0.638298 (-2750 1125);
PAINT SKYBLUE (-2750 1125);
FORCEPROP 0 LAST GROUP M2_SATA
J 0
(-2700 1225);
DISPLAY 0.638298 (-2700 1225);
PAINT BROWN (-2700 1225);
DISPLAY BOTH (-2700 1225);
FORCEPROP 1 LAST LOCATION C8F13
J 0
(-3050 1175);
DISPLAY 0.638298 (-3050 1175);
PAINT SKYBLUE (-3050 1175);
FORCEPROP 2 LAST SEC 1
J 0
(-2700 1275);
DISPLAY 0.680851 (-2700 1275);
PAINT MONO (-2700 1275);
DISPLAY INVISIBLE (-2700 1275);
FORCEPROP 2 LAST SEC_TYPE 0402V
J 0
(-2700 1275);
DISPLAY 1.021277 (-2700 1275);
PAINT ORANGE (-2700 1275);
DISPLAY INVISIBLE (-2700 1275);
FORCEPROP 2 LAST CDS_LIB dev_discrete
R 1
J 0
(-2600 1175);
PAINT MONO (-2600 1175);
DISPLAY INVISIBLE (-2600 1175);
FORCEPROP 1 LAST PATH I141
R 1
J 0
(-2750 1225);
DISPLAY 0.978723 (-2750 1225);
PAINT WHITE (-2750 1225);
DISPLAY INVISIBLE (-2750 1225);
FORCEADD CAP_A..1
R 1
(-2575 750);
FORCEPROP 1 LAST PACK_TYPE 0402V
J 0
(-2450 700);
DISPLAY 0.638298 (-2450 700);
PAINT SKYBLUE (-2450 700);
FORCEPROP 1 LAST VALUE 0.01UF
J 0
(-3000 700);
DISPLAY 0.638298 (-3000 700);
PAINT SKYBLUE (-3000 700);
FORCEPROP 1 LASTPIN (-2675 750) $PN 1
J 0
(-2680 760);
DISPLAY 0.787234 (-2680 760);
PAINT ORANGE (-2680 760);
FORCEPROP 1 LAST VOLTAGE 25V
J 0
(-2725 700);
DISPLAY 0.638298 (-2725 700);
PAINT SKYBLUE (-2725 700);
FORCEPROP 1 LAST TOLERANCE 10%
J 0
(-2850 700);
DISPLAY 0.638298 (-2850 700);
PAINT SKYBLUE (-2850 700);
FORCEPROP 1 LAST MATERIAL X7R
J 0
(-2300 700);
DISPLAY 0.638298 (-2300 700);
PAINT SKYBLUE (-2300 700);
FORCEPROP 1 LAST LOCATION C8F15
J 0
(-3025 750);
DISPLAY 0.638298 (-3025 750);
PAINT SKYBLUE (-3025 750);
FORCEPROP 1 LASTPIN (-2475 750) $PN 2
J 0
(-2505 760);
DISPLAY 0.787234 (-2505 760);
PAINT ORANGE (-2505 760);
FORCEPROP 1 LAST PART_NUMBER A36096-045
J 0
(-2450 750);
DISPLAY 0.638298 (-2450 750);
PAINT BLUE (-2450 750);
FORCEPROP 0 LAST GROUP M2_SATA
J 0
(-2675 800);
DISPLAY 0.638298 (-2675 800);
PAINT BROWN (-2675 800);
DISPLAY BOTH (-2675 800);
FORCEPROP 1 LAST PATH I142
R 1
J 0
(-2725 800);
DISPLAY 0.978723 (-2725 800);
PAINT WHITE (-2725 800);
DISPLAY INVISIBLE (-2725 800);
FORCEPROP 2 LAST SEC 1
J 0
(-2675 850);
DISPLAY 0.680851 (-2675 850);
PAINT MONO (-2675 850);
DISPLAY INVISIBLE (-2675 850);
FORCEPROP 2 LAST SEC_TYPE 0402V
J 0
(-2675 850);
DISPLAY 1.021277 (-2675 850);
PAINT ORANGE (-2675 850);
DISPLAY INVISIBLE (-2675 850);
FORCEPROP 2 LAST CDS_LIB dev_discrete
R 1
J 0
(-2575 750);
PAINT MONO (-2575 750);
DISPLAY INVISIBLE (-2575 750);
FORCEADD SKT-MINI67P-41-GP..1
(-6450 3650);
FORCEPROP 2 LASTPIN (-6750 3700) $PN 32
J 2
(-6760 3710);
DISPLAY 0.808511 (-6760 3710);
PAINT ORANGE (-6760 3710);
FORCEPROP 2 LASTPIN (-6750 3650) $PN 34
J 2
(-6760 3660);
DISPLAY 0.808511 (-6760 3660);
PAINT ORANGE (-6760 3660);
FORCEPROP 2 LASTPIN (-6750 3950) $PN 22
J 2
(-6760 3960);
DISPLAY 0.808511 (-6760 3960);
PAINT ORANGE (-6760 3960);
FORCEPROP 2 LASTPIN (-6750 3900) $PN 24
J 2
(-6760 3910);
DISPLAY 0.808511 (-6760 3910);
PAINT ORANGE (-6760 3910);
FORCEPROP 2 LASTPIN (-6150 4450) $PN 3
J 0
(-6140 4460);
DISPLAY 0.808511 (-6140 4460);
PAINT ORANGE (-6140 4460);
FORCEPROP 2 LASTPIN (-6150 3700) $PN 33
J 0
(-6140 3710);
DISPLAY 0.808511 (-6140 3710);
PAINT ORANGE (-6140 3710);
FORCEPROP 2 LASTPIN (-6150 3750) $PN 31
J 0
(-6140 3760);
DISPLAY 0.808511 (-6140 3760);
PAINT ORANGE (-6140 3760);
FORCEPROP 2 LASTPIN (-6750 2850) $PN 72
J 2
(-6760 2860);
DISPLAY 0.808511 (-6760 2860);
PAINT ORANGE (-6760 2860);
FORCEPROP 2 LASTPIN (-6650 2700) $PN NP2
J 2
(-6660 2710);
DISPLAY 0.808511 (-6660 2710);
PAINT ORANGE (-6660 2710);
FORCEPROP 2 LASTPIN (-6150 3200) $PN 53
J 0
(-6140 3210);
DISPLAY 0.808511 (-6140 3210);
PAINT ORANGE (-6140 3210);
FORCEPROP 1 LAST VALUE SKT-MINI67P-41-GP
J 0
(-6600 2550);
DISPLAY 0.617021 (-6600 2550);
PAINT GREEN (-6600 2550);
FORCEPROP 2 LASTPIN (-6150 4350) $PN 7
J 0
(-6140 4360);
DISPLAY 0.808511 (-6140 4360);
PAINT ORANGE (-6140 4360);
FORCEPROP 2 LASTPIN (-6150 4250) $PN 11
J 0
(-6140 4260);
DISPLAY 0.808511 (-6140 4260);
PAINT ORANGE (-6140 4260);
FORCEPROP 2 LASTPIN (-6150 4100) $PN 17
J 0
(-6140 4110);
DISPLAY 0.808511 (-6140 4110);
PAINT ORANGE (-6140 4110);
FORCEPROP 2 LASTPIN (-6150 3450) $PN 43
J 0
(-6140 3460);
DISPLAY 0.808511 (-6140 3460);
PAINT ORANGE (-6140 3460);
FORCEPROP 2 LASTPIN (-6150 3400) $PN 45
J 0
(-6140 3410);
DISPLAY 0.808511 (-6140 3410);
PAINT ORANGE (-6140 3410);
FORCEPROP 2 LASTPIN (-6150 3350) $PN 47
J 0
(-6140 3360);
DISPLAY 0.808511 (-6140 3360);
PAINT ORANGE (-6140 3360);
FORCEPROP 2 LASTPIN (-6750 4450) $PN 2
J 2
(-6760 4460);
DISPLAY 0.808511 (-6760 4460);
PAINT ORANGE (-6760 4460);
FORCEPROP 2 LASTPIN (-6750 4400) $PN 4
J 2
(-6760 4410);
DISPLAY 0.808511 (-6760 4410);
PAINT ORANGE (-6760 4410);
FORCEPROP 2 LASTPIN (-6750 4350) $PN 6
J 2
(-6760 4360);
DISPLAY 0.808511 (-6760 4360);
PAINT ORANGE (-6760 4360);
FORCEPROP 2 LASTPIN (-6750 3250) $PN 50
J 2
(-6760 3260);
DISPLAY 0.808511 (-6760 3260);
PAINT ORANGE (-6760 3260);
FORCEPROP 2 LASTPIN (-6750 3200) $PN 52
J 2
(-6760 3210);
DISPLAY 0.808511 (-6760 3210);
PAINT ORANGE (-6760 3210);
FORCEPROP 2 LASTPIN (-6750 3150) $PN 54
J 2
(-6760 3160);
DISPLAY 0.808511 (-6760 3160);
PAINT ORANGE (-6760 3160);
FORCEPROP 2 LASTPIN (-6750 3100) $PN 56
J 2
(-6760 3110);
DISPLAY 0.808511 (-6760 3110);
PAINT ORANGE (-6760 3110);
FORCEPROP 2 LASTPIN (-6750 3050) $PN 58
J 2
(-6760 3060);
DISPLAY 0.808511 (-6760 3060);
PAINT ORANGE (-6760 3060);
FORCEPROP 2 LASTPIN (-6750 2950) $PN 68
J 2
(-6760 2960);
DISPLAY 0.808511 (-6760 2960);
PAINT ORANGE (-6760 2960);
FORCEPROP 2 LASTPIN (-6750 2900) $PN 70
J 2
(-6760 2910);
DISPLAY 0.808511 (-6760 2910);
PAINT ORANGE (-6760 2910);
FORCEPROP 2 LASTPIN (-6150 4650) $PN 76
J 0
(-6140 4660);
DISPLAY 0.808511 (-6140 4660);
PAINT ORANGE (-6140 4660);
FORCEPROP 2 LASTPIN (-6650 4600) $PN NP1
J 2
(-6660 4610);
DISPLAY 0.808511 (-6660 4610);
PAINT ORANGE (-6660 4610);
FORCEPROP 1 LAST LOCATION J8F1
J 0
(-6625 4725);
DISPLAY 0.617021 (-6625 4725);
PAINT GREEN (-6625 4725);
FORCEPROP 2 LASTPIN (-6150 3100) $PN 57
J 0
(-6140 3110);
DISPLAY 0.808511 (-6140 3110);
PAINT ORANGE (-6140 3110);
FORCEPROP 2 LASTPIN (-6150 3300) $PN 49
J 0
(-6140 3310);
DISPLAY 0.808511 (-6140 3310);
PAINT ORANGE (-6140 3310);
FORCEPROP 2 LASTPIN (-6150 3000) $PN 67
J 0
(-6140 3010);
DISPLAY 0.808511 (-6140 3010);
PAINT ORANGE (-6140 3010);
FORCEPROP 2 LASTPIN (-6150 2900) $PN 71
J 0
(-6140 2910);
DISPLAY 0.808511 (-6140 2910);
PAINT ORANGE (-6140 2910);
FORCEPROP 2 LASTPIN (-6150 2850) $PN 73
J 0
(-6140 2860);
DISPLAY 0.808511 (-6140 2860);
PAINT ORANGE (-6140 2860);
FORCEPROP 2 LASTPIN (-6150 2800) $PN 75
J 0
(-6140 2810);
DISPLAY 0.808511 (-6140 2810);
PAINT ORANGE (-6140 2810);
FORCEPROP 2 LASTPIN (-6150 2650) $PN 77
J 0
(-6140 2660);
DISPLAY 0.808511 (-6140 2660);
PAINT ORANGE (-6140 2660);
FORCEPROP 2 LASTPIN (-6150 3600) $PN 37
J 0
(-6140 3610);
DISPLAY 0.808511 (-6140 3610);
PAINT ORANGE (-6140 3610);
FORCEPROP 2 LASTPIN (-6150 3800) $PN 29
J 0
(-6140 3810);
DISPLAY 0.808511 (-6140 3810);
PAINT ORANGE (-6140 3810);
FORCEPROP 2 LASTPIN (-6150 3850) $PN 27
J 0
(-6140 3860);
DISPLAY 0.808511 (-6140 3860);
PAINT ORANGE (-6140 3860);
FORCEPROP 2 LASTPIN (-6150 3900) $PN 25
J 0
(-6140 3910);
DISPLAY 0.808511 (-6140 3910);
PAINT ORANGE (-6140 3910);
FORCEPROP 2 LASTPIN (-6150 3950) $PN 23
J 0
(-6140 3960);
DISPLAY 0.808511 (-6140 3960);
PAINT ORANGE (-6140 3960);
FORCEPROP 2 LASTPIN (-6750 2800) $PN 74
J 2
(-6760 2810);
DISPLAY 0.808511 (-6760 2810);
PAINT ORANGE (-6760 2810);
FORCEPROP 2 LASTPIN (-6150 2950) $PN 69
J 0
(-6140 2960);
DISPLAY 0.808511 (-6140 2960);
PAINT ORANGE (-6140 2960);
FORCEPROP 2 LASTPIN (-6150 4550) $PN 1
J 0
(-6140 4560);
DISPLAY 0.808511 (-6140 4560);
PAINT ORANGE (-6140 4560);
FORCEPROP 2 LASTPIN (-6150 4400) $PN 5
J 0
(-6140 4410);
DISPLAY 0.808511 (-6140 4410);
PAINT ORANGE (-6140 4410);
FORCEPROP 2 LASTPIN (-6750 4200) $PN 12
J 2
(-6760 4210);
DISPLAY 0.808511 (-6760 4210);
PAINT ORANGE (-6760 4210);
FORCEPROP 2 LASTPIN (-6150 3150) $PN 55
J 0
(-6140 3160);
DISPLAY 0.808511 (-6140 3160);
PAINT ORANGE (-6140 3160);
FORCEPROP 2 LASTPIN (-6150 3550) $PN 39
J 0
(-6140 3560);
DISPLAY 0.808511 (-6140 3560);
PAINT ORANGE (-6140 3560);
FORCEPROP 2 LASTPIN (-6750 3800) $PN 28
J 2
(-6760 3810);
DISPLAY 0.808511 (-6760 3810);
PAINT ORANGE (-6760 3810);
FORCEPROP 2 LASTPIN (-6750 3850) $PN 26
J 2
(-6760 3860);
DISPLAY 0.808511 (-6760 3860);
PAINT ORANGE (-6760 3860);
FORCEPROP 2 LASTPIN (-6750 3550) $PN 38
J 2
(-6760 3560);
DISPLAY 0.808511 (-6760 3560);
PAINT ORANGE (-6760 3560);
FORCEPROP 2 LASTPIN (-6150 4300) $PN 9
J 0
(-6140 4310);
DISPLAY 0.808511 (-6140 4310);
PAINT ORANGE (-6140 4310);
FORCEPROP 2 LASTPIN (-6150 3250) $PN 51
J 0
(-6140 3260);
DISPLAY 0.808511 (-6140 3260);
PAINT ORANGE (-6140 3260);
FORCEPROP 2 LASTPIN (-6750 4250) $PN 10
J 2
(-6760 4260);
DISPLAY 0.808511 (-6760 4260);
PAINT ORANGE (-6760 4260);
FORCEPROP 2 LASTPIN (-6750 4300) $PN 8
J 2
(-6760 4310);
DISPLAY 0.808511 (-6760 4310);
PAINT ORANGE (-6760 4310);
FORCEPROP 2 LASTPIN (-6750 4050) $PN 18
J 2
(-6760 4060);
DISPLAY 0.808511 (-6760 4060);
PAINT ORANGE (-6760 4060);
FORCEPROP 2 LASTPIN (-6750 4000) $PN 20
J 2
(-6760 4010);
DISPLAY 0.808511 (-6760 4010);
PAINT ORANGE (-6760 4010);
FORCEPROP 2 LASTPIN (-6750 4100) $PN 16
J 2
(-6760 4110);
DISPLAY 0.808511 (-6760 4110);
PAINT ORANGE (-6760 4110);
FORCEPROP 2 LASTPIN (-6150 4200) $PN 13
J 0
(-6140 4210);
DISPLAY 0.808511 (-6140 4210);
PAINT ORANGE (-6140 4210);
FORCEPROP 2 LASTPIN (-6150 4150) $PN 15
J 0
(-6140 4160);
DISPLAY 0.808511 (-6140 4160);
PAINT ORANGE (-6140 4160);
FORCEPROP 2 LASTPIN (-6150 4050) $PN 19
J 0
(-6140 4060);
DISPLAY 0.808511 (-6140 4060);
PAINT ORANGE (-6140 4060);
FORCEPROP 2 LASTPIN (-6150 4000) $PN 21
J 0
(-6140 4010);
DISPLAY 0.808511 (-6140 4010);
PAINT ORANGE (-6140 4010);
FORCEPROP 2 LASTPIN (-6150 3650) $PN 35
J 0
(-6140 3660);
DISPLAY 0.808511 (-6140 3660);
PAINT ORANGE (-6140 3660);
FORCEPROP 2 LASTPIN (-6150 3500) $PN 41
J 0
(-6140 3510);
DISPLAY 0.808511 (-6140 3510);
PAINT ORANGE (-6140 3510);
FORCEPROP 2 LASTPIN (-6750 4150) $PN 14
J 2
(-6760 4160);
DISPLAY 0.808511 (-6760 4160);
PAINT ORANGE (-6760 4160);
FORCEPROP 2 LASTPIN (-6750 3300) $PN 48
J 2
(-6760 3310);
DISPLAY 0.808511 (-6760 3310);
PAINT ORANGE (-6760 3310);
FORCEPROP 2 LASTPIN (-6750 3600) $PN 36
J 2
(-6760 3610);
DISPLAY 0.808511 (-6760 3610);
PAINT ORANGE (-6760 3610);
FORCEPROP 2 LASTPIN (-6750 3750) $PN 30
J 2
(-6760 3760);
DISPLAY 0.808511 (-6760 3760);
PAINT ORANGE (-6760 3760);
FORCEPROP 2 LASTPIN (-6750 3500) $PN 40
J 2
(-6760 3510);
DISPLAY 0.808511 (-6760 3510);
PAINT ORANGE (-6760 3510);
FORCEPROP 2 LASTPIN (-6750 3450) $PN 42
J 2
(-6760 3460);
DISPLAY 0.808511 (-6760 3460);
PAINT ORANGE (-6760 3460);
FORCEPROP 2 LASTPIN (-6750 3400) $PN 44
J 2
(-6760 3410);
DISPLAY 0.808511 (-6760 3410);
PAINT ORANGE (-6760 3410);
FORCEPROP 2 LASTPIN (-6750 3350) $PN 46
J 2
(-6760 3360);
DISPLAY 0.808511 (-6760 3360);
PAINT ORANGE (-6760 3360);
FORCEPROP 1 LAST CDS_LMAN_SYM_OUTLINE -150,1050,150,-1050
J 0
(-6450 3650);
DISPLAY 0.468085 (-6450 3650);
PAINT GREEN (-6450 3650);
DISPLAY INVISIBLE (-6450 3650);
FORCEPROP 1 LAST PATH I143
J 0
(-6450 3690);
DISPLAY 0.617021 (-6450 3690);
PAINT GREEN (-6450 3690);
DISPLAY INVISIBLE (-6450 3690);
FORCEPROP 2 LAST CDS_LIB w_hdl
J 0
(-6450 3650);
PAINT MONO (-6450 3650);
DISPLAY INVISIBLE (-6450 3650);
FORCEPROP 1 LAST PART_NUMBER 062.10003.0B21
J 0
(-6450 3610);
DISPLAY 0.617021 (-6450 3610);
PAINT GREEN (-6450 3610);
DISPLAY INVISIBLE (-6450 3610);
FORCEPROP 2 LAST SEC_TYPE SOCKET-G4
J 0
(-6625 4775);
DISPLAY 1.021277 (-6625 4775);
PAINT ORANGE (-6625 4775);
DISPLAY INVISIBLE (-6625 4775);
FORCEPROP 2 LAST SEC 1
J 0
(-6625 4775);
DISPLAY 0.680851 (-6625 4775);
PAINT MONO (-6625 4775);
DISPLAY INVISIBLE (-6625 4775);
FORCEPROP 1 LAST PACK_TYPE SOCKET-G4
J 0
(-6450 3650);
DISPLAY 0.617021 (-6450 3650);
PAINT GREEN (-6450 3650);
DISPLAY INVISIBLE (-6450 3650);
FORCEADD GND..1
(-6000 2550);
FORCEPROP 3 LASTPIN (-6000 2600) SIG_NAME GND\g
J 0
(-5990 2610);
DISPLAY 0.659574 (-5990 2610);
PAINT MONO (-5990 2610);
DISPLAY INVISIBLE (-5990 2610);
FORCEPROP 1 LAST PATH I144
J 0
(-5925 2550);
DISPLAY 0.872340 (-5925 2550);
PAINT AQUA (-5925 2550);
DISPLAY INVISIBLE (-5925 2550);
FORCEPROP 1 LAST HDL_POWER GND
J 0
(-6000 2700);
DISPLAY 0.872340 (-6000 2700);
PAINT GREEN (-6000 2700);
DISPLAY INVISIBLE (-6000 2700);
FORCEPROP 1 LAST VOLTAGE 0.0V
J 0
(-6045 2507);
DISPLAY 0.340426 (-6045 2507);
PAINT SKYBLUE (-6045 2507);
DISPLAY INVISIBLE (-6045 2507);
FORCEPROP 2 LAST CDS_LIB mstr_symbols
J 0
(-6000 2550);
PAINT ORANGE (-6000 2550);
DISPLAY INVISIBLE (-6000 2550);
FORCEPROP 1 LAST SIZE 1B
J 0
(-5925 2500);
DISPLAY 0.872340 (-5925 2500);
PAINT AQUA (-5925 2500);
DISPLAY INVISIBLE (-5925 2500);
FORCEPROP 1 LAST BODY_TYPE PLUMBING
J 0
(-6045 2507);
DISPLAY 0.340426 (-6045 2507);
PAINT GREEN (-6045 2507);
DISPLAY INVISIBLE (-6045 2507);
FORCEADD GND..1
(-5900 4550);
FORCEPROP 3 LASTPIN (-5900 4600) SIG_NAME GND\g
J 0
(-5890 4610);
DISPLAY 0.659574 (-5890 4610);
PAINT MONO (-5890 4610);
DISPLAY INVISIBLE (-5890 4610);
FORCEPROP 1 LAST PATH I145
J 0
(-5825 4550);
DISPLAY 0.872340 (-5825 4550);
PAINT AQUA (-5825 4550);
DISPLAY INVISIBLE (-5825 4550);
FORCEPROP 1 LAST HDL_POWER GND
J 0
(-5900 4700);
DISPLAY 0.872340 (-5900 4700);
PAINT GREEN (-5900 4700);
DISPLAY INVISIBLE (-5900 4700);
FORCEPROP 1 LAST VOLTAGE 0.0V
J 0
(-5945 4507);
DISPLAY 0.340426 (-5945 4507);
PAINT SKYBLUE (-5945 4507);
DISPLAY INVISIBLE (-5945 4507);
FORCEPROP 2 LAST CDS_LIB mstr_symbols
J 0
(-5900 4550);
PAINT ORANGE (-5900 4550);
DISPLAY INVISIBLE (-5900 4550);
FORCEPROP 1 LAST SIZE 1B
J 0
(-5825 4500);
DISPLAY 0.872340 (-5825 4500);
PAINT AQUA (-5825 4500);
DISPLAY INVISIBLE (-5825 4500);
FORCEPROP 1 LAST BODY_TYPE PLUMBING
J 0
(-5945 4507);
DISPLAY 0.340426 (-5945 4507);
PAINT GREEN (-5945 4507);
DISPLAY INVISIBLE (-5945 4507);
FORCEADD GND..1
R 1
(-5950 4300);
FORCEPROP 3 LASTPIN (-6000 4300) SIG_NAME GND\g
J 0
(-5990 4310);
DISPLAY 0.659574 (-5990 4310);
PAINT MONO (-5990 4310);
DISPLAY INVISIBLE (-5990 4310);
FORCEPROP 1 LAST PATH I146
R 1
J 0
(-5950 4375);
DISPLAY 0.872340 (-5950 4375);
PAINT AQUA (-5950 4375);
DISPLAY INVISIBLE (-5950 4375);
FORCEPROP 1 LAST HDL_POWER GND
R 1
J 0
(-6100 4300);
DISPLAY 0.872340 (-6100 4300);
PAINT GREEN (-6100 4300);
DISPLAY INVISIBLE (-6100 4300);
FORCEPROP 1 LAST VOLTAGE 0.0V
R 1
J 0
(-5907 4255);
DISPLAY 0.340426 (-5907 4255);
PAINT SKYBLUE (-5907 4255);
DISPLAY INVISIBLE (-5907 4255);
FORCEPROP 2 LAST CDS_LIB mstr_symbols
R 1
J 0
(-5950 4300);
PAINT ORANGE (-5950 4300);
DISPLAY INVISIBLE (-5950 4300);
FORCEPROP 1 LAST SIZE 1B
R 1
J 0
(-5900 4375);
DISPLAY 0.872340 (-5900 4375);
PAINT AQUA (-5900 4375);
DISPLAY INVISIBLE (-5900 4375);
FORCEPROP 1 LAST BODY_TYPE PLUMBING
R 1
J 0
(-5907 4255);
DISPLAY 0.340426 (-5907 4255);
PAINT GREEN (-5907 4255);
DISPLAY INVISIBLE (-5907 4255);
FORCEADD GND..1
R 1
(-5950 4150);
FORCEPROP 3 LASTPIN (-6000 4150) SIG_NAME GND\g
J 0
(-5990 4160);
DISPLAY 0.659574 (-5990 4160);
PAINT MONO (-5990 4160);
DISPLAY INVISIBLE (-5990 4160);
FORCEPROP 1 LAST HDL_POWER GND
R 1
J 0
(-6100 4150);
DISPLAY 0.872340 (-6100 4150);
PAINT GREEN (-6100 4150);
DISPLAY INVISIBLE (-6100 4150);
FORCEPROP 1 LAST VOLTAGE 0.0V
R 1
J 0
(-5907 4105);
DISPLAY 0.340426 (-5907 4105);
PAINT SKYBLUE (-5907 4105);
DISPLAY INVISIBLE (-5907 4105);
FORCEPROP 2 LAST CDS_LIB mstr_symbols
R 1
J 0
(-5950 4150);
PAINT ORANGE (-5950 4150);
DISPLAY INVISIBLE (-5950 4150);
FORCEPROP 1 LAST SIZE 1B
R 1
J 0
(-5900 4225);
DISPLAY 0.872340 (-5900 4225);
PAINT AQUA (-5900 4225);
DISPLAY INVISIBLE (-5900 4225);
FORCEPROP 1 LAST BODY_TYPE PLUMBING
R 1
J 0
(-5907 4105);
DISPLAY 0.340426 (-5907 4105);
PAINT GREEN (-5907 4105);
DISPLAY INVISIBLE (-5907 4105);
FORCEPROP 1 LAST PATH I147
R 1
J 0
(-5950 4225);
DISPLAY 0.872340 (-5950 4225);
PAINT AQUA (-5950 4225);
DISPLAY INVISIBLE (-5950 4225);
FORCEADD GND..1
R 1
(-5950 4000);
FORCEPROP 3 LASTPIN (-6000 4000) SIG_NAME GND\g
J 0
(-5990 4010);
DISPLAY 0.659574 (-5990 4010);
PAINT MONO (-5990 4010);
DISPLAY INVISIBLE (-5990 4010);
FORCEPROP 1 LAST HDL_POWER GND
R 1
J 0
(-6100 4000);
DISPLAY 0.872340 (-6100 4000);
PAINT GREEN (-6100 4000);
DISPLAY INVISIBLE (-6100 4000);
FORCEPROP 1 LAST VOLTAGE 0.0V
R 1
J 0
(-5907 3955);
DISPLAY 0.340426 (-5907 3955);
PAINT SKYBLUE (-5907 3955);
DISPLAY INVISIBLE (-5907 3955);
FORCEPROP 2 LAST CDS_LIB mstr_symbols
R 1
J 0
(-5950 4000);
PAINT ORANGE (-5950 4000);
DISPLAY INVISIBLE (-5950 4000);
FORCEPROP 1 LAST SIZE 1B
R 1
J 0
(-5900 4075);
DISPLAY 0.872340 (-5900 4075);
PAINT AQUA (-5900 4075);
DISPLAY INVISIBLE (-5900 4075);
FORCEPROP 1 LAST BODY_TYPE PLUMBING
R 1
J 0
(-5907 3955);
DISPLAY 0.340426 (-5907 3955);
PAINT GREEN (-5907 3955);
DISPLAY INVISIBLE (-5907 3955);
FORCEPROP 1 LAST PATH I148
R 1
J 0
(-5950 4075);
DISPLAY 0.872340 (-5950 4075);
PAINT AQUA (-5950 4075);
DISPLAY INVISIBLE (-5950 4075);
FORCEADD GND..1
R 1
(-5950 3850);
FORCEPROP 3 LASTPIN (-6000 3850) SIG_NAME GND\g
J 0
(-5990 3860);
DISPLAY 0.659574 (-5990 3860);
PAINT MONO (-5990 3860);
DISPLAY INVISIBLE (-5990 3860);
FORCEPROP 1 LAST HDL_POWER GND
R 1
J 0
(-6100 3850);
DISPLAY 0.872340 (-6100 3850);
PAINT GREEN (-6100 3850);
DISPLAY INVISIBLE (-6100 3850);
FORCEPROP 1 LAST VOLTAGE 0.0V
R 1
J 0
(-5907 3805);
DISPLAY 0.340426 (-5907 3805);
PAINT SKYBLUE (-5907 3805);
DISPLAY INVISIBLE (-5907 3805);
FORCEPROP 2 LAST CDS_LIB mstr_symbols
R 1
J 0
(-5950 3850);
PAINT ORANGE (-5950 3850);
DISPLAY INVISIBLE (-5950 3850);
FORCEPROP 1 LAST SIZE 1B
R 1
J 0
(-5900 3925);
DISPLAY 0.872340 (-5900 3925);
PAINT AQUA (-5900 3925);
DISPLAY INVISIBLE (-5900 3925);
FORCEPROP 1 LAST BODY_TYPE PLUMBING
R 1
J 0
(-5907 3805);
DISPLAY 0.340426 (-5907 3805);
PAINT GREEN (-5907 3805);
DISPLAY INVISIBLE (-5907 3805);
FORCEPROP 1 LAST PATH I149
R 1
J 0
(-5950 3925);
DISPLAY 0.872340 (-5950 3925);
PAINT AQUA (-5950 3925);
DISPLAY INVISIBLE (-5950 3925);
FORCEADD GND..1
R 1
(-5950 3700);
FORCEPROP 3 LASTPIN (-6000 3700) SIG_NAME GND\g
J 0
(-5990 3710);
DISPLAY 0.659574 (-5990 3710);
PAINT MONO (-5990 3710);
DISPLAY INVISIBLE (-5990 3710);
FORCEPROP 1 LAST PATH I150
R 1
J 0
(-5950 3775);
DISPLAY 0.872340 (-5950 3775);
PAINT AQUA (-5950 3775);
DISPLAY INVISIBLE (-5950 3775);
FORCEPROP 1 LAST BODY_TYPE PLUMBING
R 1
J 0
(-5907 3655);
DISPLAY 0.340426 (-5907 3655);
PAINT GREEN (-5907 3655);
DISPLAY INVISIBLE (-5907 3655);
FORCEPROP 1 LAST SIZE 1B
R 1
J 0
(-5900 3775);
DISPLAY 0.872340 (-5900 3775);
PAINT AQUA (-5900 3775);
DISPLAY INVISIBLE (-5900 3775);
FORCEPROP 2 LAST CDS_LIB mstr_symbols
R 1
J 0
(-5950 3700);
PAINT ORANGE (-5950 3700);
DISPLAY INVISIBLE (-5950 3700);
FORCEPROP 1 LAST VOLTAGE 0.0V
R 1
J 0
(-5907 3655);
DISPLAY 0.340426 (-5907 3655);
PAINT SKYBLUE (-5907 3655);
DISPLAY INVISIBLE (-5907 3655);
FORCEPROP 1 LAST HDL_POWER GND
R 1
J 0
(-6100 3700);
DISPLAY 0.872340 (-6100 3700);
PAINT GREEN (-6100 3700);
DISPLAY INVISIBLE (-6100 3700);
FORCEADD GND..1
R 1
(-5950 3550);
FORCEPROP 3 LASTPIN (-6000 3550) SIG_NAME GND\g
J 0
(-5990 3560);
DISPLAY 0.659574 (-5990 3560);
PAINT MONO (-5990 3560);
DISPLAY INVISIBLE (-5990 3560);
FORCEPROP 1 LAST PATH I151
R 1
J 0
(-5950 3625);
DISPLAY 0.872340 (-5950 3625);
PAINT AQUA (-5950 3625);
DISPLAY INVISIBLE (-5950 3625);
FORCEPROP 1 LAST BODY_TYPE PLUMBING
R 1
J 0
(-5907 3505);
DISPLAY 0.340426 (-5907 3505);
PAINT GREEN (-5907 3505);
DISPLAY INVISIBLE (-5907 3505);
FORCEPROP 1 LAST SIZE 1B
R 1
J 0
(-5900 3625);
DISPLAY 0.872340 (-5900 3625);
PAINT AQUA (-5900 3625);
DISPLAY INVISIBLE (-5900 3625);
FORCEPROP 2 LAST CDS_LIB mstr_symbols
R 1
J 0
(-5950 3550);
PAINT ORANGE (-5950 3550);
DISPLAY INVISIBLE (-5950 3550);
FORCEPROP 1 LAST VOLTAGE 0.0V
R 1
J 0
(-5907 3505);
DISPLAY 0.340426 (-5907 3505);
PAINT SKYBLUE (-5907 3505);
DISPLAY INVISIBLE (-5907 3505);
FORCEPROP 1 LAST HDL_POWER GND
R 1
J 0
(-6100 3550);
DISPLAY 0.872340 (-6100 3550);
PAINT GREEN (-6100 3550);
DISPLAY INVISIBLE (-6100 3550);
FORCEADD GND..1
R 1
(-5950 3400);
FORCEPROP 3 LASTPIN (-6000 3400) SIG_NAME GND\g
J 0
(-5990 3410);
DISPLAY 0.659574 (-5990 3410);
PAINT MONO (-5990 3410);
DISPLAY INVISIBLE (-5990 3410);
FORCEPROP 1 LAST PATH I152
R 1
J 0
(-5950 3475);
DISPLAY 0.872340 (-5950 3475);
PAINT AQUA (-5950 3475);
DISPLAY INVISIBLE (-5950 3475);
FORCEPROP 1 LAST BODY_TYPE PLUMBING
R 1
J 0
(-5907 3355);
DISPLAY 0.340426 (-5907 3355);
PAINT GREEN (-5907 3355);
DISPLAY INVISIBLE (-5907 3355);
FORCEPROP 1 LAST SIZE 1B
R 1
J 0
(-5900 3475);
DISPLAY 0.872340 (-5900 3475);
PAINT AQUA (-5900 3475);
DISPLAY INVISIBLE (-5900 3475);
FORCEPROP 2 LAST CDS_LIB mstr_symbols
R 1
J 0
(-5950 3400);
PAINT ORANGE (-5950 3400);
DISPLAY INVISIBLE (-5950 3400);
FORCEPROP 1 LAST VOLTAGE 0.0V
R 1
J 0
(-5907 3355);
DISPLAY 0.340426 (-5907 3355);
PAINT SKYBLUE (-5907 3355);
DISPLAY INVISIBLE (-5907 3355);
FORCEPROP 1 LAST HDL_POWER GND
R 1
J 0
(-6100 3400);
DISPLAY 0.872340 (-6100 3400);
PAINT GREEN (-6100 3400);
DISPLAY INVISIBLE (-6100 3400);
FORCEADD GND..1
R 1
(-5950 3250);
FORCEPROP 3 LASTPIN (-6000 3250) SIG_NAME GND\g
J 0
(-5990 3260);
DISPLAY 0.659574 (-5990 3260);
PAINT MONO (-5990 3260);
DISPLAY INVISIBLE (-5990 3260);
FORCEPROP 1 LAST PATH I153
R 1
J 0
(-5950 3325);
DISPLAY 0.872340 (-5950 3325);
PAINT AQUA (-5950 3325);
DISPLAY INVISIBLE (-5950 3325);
FORCEPROP 1 LAST BODY_TYPE PLUMBING
R 1
J 0
(-5907 3205);
DISPLAY 0.340426 (-5907 3205);
PAINT GREEN (-5907 3205);
DISPLAY INVISIBLE (-5907 3205);
FORCEPROP 1 LAST SIZE 1B
R 1
J 0
(-5900 3325);
DISPLAY 0.872340 (-5900 3325);
PAINT AQUA (-5900 3325);
DISPLAY INVISIBLE (-5900 3325);
FORCEPROP 2 LAST CDS_LIB mstr_symbols
R 1
J 0
(-5950 3250);
PAINT ORANGE (-5950 3250);
DISPLAY INVISIBLE (-5950 3250);
FORCEPROP 1 LAST VOLTAGE 0.0V
R 1
J 0
(-5907 3205);
DISPLAY 0.340426 (-5907 3205);
PAINT SKYBLUE (-5907 3205);
DISPLAY INVISIBLE (-5907 3205);
FORCEPROP 1 LAST HDL_POWER GND
R 1
J 0
(-6100 3250);
DISPLAY 0.872340 (-6100 3250);
PAINT GREEN (-6100 3250);
DISPLAY INVISIBLE (-6100 3250);
FORCEADD GND..1
R 1
(-5950 3100);
FORCEPROP 3 LASTPIN (-6000 3100) SIG_NAME GND\g
J 0
(-5990 3110);
DISPLAY 0.659574 (-5990 3110);
PAINT MONO (-5990 3110);
DISPLAY INVISIBLE (-5990 3110);
FORCEPROP 1 LAST HDL_POWER GND
R 1
J 0
(-6100 3100);
DISPLAY 0.872340 (-6100 3100);
PAINT GREEN (-6100 3100);
DISPLAY INVISIBLE (-6100 3100);
FORCEPROP 1 LAST VOLTAGE 0.0V
R 1
J 0
(-5907 3055);
DISPLAY 0.340426 (-5907 3055);
PAINT SKYBLUE (-5907 3055);
DISPLAY INVISIBLE (-5907 3055);
FORCEPROP 2 LAST CDS_LIB mstr_symbols
R 1
J 0
(-5950 3100);
PAINT ORANGE (-5950 3100);
DISPLAY INVISIBLE (-5950 3100);
FORCEPROP 1 LAST SIZE 1B
R 1
J 0
(-5900 3175);
DISPLAY 0.872340 (-5900 3175);
PAINT AQUA (-5900 3175);
DISPLAY INVISIBLE (-5900 3175);
FORCEPROP 1 LAST BODY_TYPE PLUMBING
R 1
J 0
(-5907 3055);
DISPLAY 0.340426 (-5907 3055);
PAINT GREEN (-5907 3055);
DISPLAY INVISIBLE (-5907 3055);
FORCEPROP 1 LAST PATH I154
R 1
J 0
(-5950 3175);
DISPLAY 0.872340 (-5950 3175);
PAINT AQUA (-5950 3175);
DISPLAY INVISIBLE (-5950 3175);
FORCEADD P3V3..1
(-7550 4550);
FORCEPROP 3 LASTPIN (-7550 4500) SIG_NAME P3V3\g
J 0
(-7540 4510);
DISPLAY 0.659574 (-7540 4510);
PAINT MONO (-7540 4510);
DISPLAY INVISIBLE (-7540 4510);
FORCEPROP 1 LAST HDL_POWER P3V3
J 0
(-7875 4425);
DISPLAY 0.872340 (-7875 4425);
PAINT ORANGE (-7875 4425);
DISPLAY INVISIBLE (-7875 4425);
FORCEPROP 1 LAST BODY_TYPE PLUMBING
J 0
(-7595 4507);
DISPLAY 0.340426 (-7595 4507);
PAINT GREEN (-7595 4507);
DISPLAY INVISIBLE (-7595 4507);
FORCEPROP 2 LAST CDS_LIB mstr_symbols
J 0
(-7550 4550);
PAINT ORANGE (-7550 4550);
DISPLAY INVISIBLE (-7550 4550);
FORCEPROP 1 LAST SIZE 1B
J 0
(-7505 4572);
DISPLAY 0.340426 (-7505 4572);
PAINT GREEN (-7505 4572);
DISPLAY INVISIBLE (-7505 4572);
FORCEPROP 1 LAST VOLTAGE 3.3V
J 0
(-7595 4507);
DISPLAY 0.340426 (-7595 4507);
PAINT SKYBLUE (-7595 4507);
DISPLAY INVISIBLE (-7595 4507);
FORCEPROP 1 LAST PATH I155
J 0
(-7505 4552);
DISPLAY 0.340426 (-7505 4552);
PAINT GREEN (-7505 4552);
DISPLAY INVISIBLE (-7505 4552);
FORCEADD P3V3..1
(-7550 3000);
FORCEPROP 3 LASTPIN (-7550 2950) SIG_NAME P3V3\g
J 0
(-7540 2960);
DISPLAY 0.659574 (-7540 2960);
PAINT MONO (-7540 2960);
DISPLAY INVISIBLE (-7540 2960);
FORCEPROP 1 LAST VOLTAGE 3.3V
J 0
(-7595 2957);
DISPLAY 0.340426 (-7595 2957);
PAINT SKYBLUE (-7595 2957);
DISPLAY INVISIBLE (-7595 2957);
FORCEPROP 1 LAST SIZE 1B
J 0
(-7505 3022);
DISPLAY 0.340426 (-7505 3022);
PAINT GREEN (-7505 3022);
DISPLAY INVISIBLE (-7505 3022);
FORCEPROP 2 LAST CDS_LIB mstr_symbols
J 0
(-7550 3000);
PAINT ORANGE (-7550 3000);
DISPLAY INVISIBLE (-7550 3000);
FORCEPROP 1 LAST BODY_TYPE PLUMBING
J 0
(-7595 2957);
DISPLAY 0.340426 (-7595 2957);
PAINT GREEN (-7595 2957);
DISPLAY INVISIBLE (-7595 2957);
FORCEPROP 1 LAST HDL_POWER P3V3
J 0
(-7875 2875);
DISPLAY 0.872340 (-7875 2875);
PAINT ORANGE (-7875 2875);
DISPLAY INVISIBLE (-7875 2875);
FORCEPROP 1 LAST PATH I156
J 0
(-7505 3002);
DISPLAY 0.340426 (-7505 3002);
PAINT GREEN (-7505 3002);
DISPLAY INVISIBLE (-7505 3002);
FORCEADD OFFPAGE..1
(-7550 3250);
FORCEPROP 2 LAST $XR0 248 
J 0
(-7802 3250);
DISPLAY 0.638298 (-7802 3250);
PAINT MONO (-7802 3250);
FORCEPROP 2 LAST CDS_LIB mstr_standard
J 0
(-7550 3250);
PAINT MONO (-7550 3250);
DISPLAY INVISIBLE (-7550 3250);
FORCEPROP 2 LAST PATH I157
J 0
(-7500 3325);
DISPLAY 1.021277 (-7500 3325);
PAINT ORANGE (-7500 3325);
DISPLAY INVISIBLE (-7500 3325);
FORCEPROP 1 LAST OFFPAGE TRUE
J 0
(-7225 3125);
DISPLAY 0.872340 (-7225 3125);
PAINT GREEN (-7225 3125);
DISPLAY INVISIBLE (-7225 3125);
FORCEPROP 1 LAST COMMENT_BODY TRUE
J 0
(-7425 3150);
DISPLAY 0.872340 (-7425 3150);
PAINT GREEN (-7425 3150);
DISPLAY INVISIBLE (-7425 3150);
FORCEADD OFFPAGE..5
(-7800 3150);
FORCEPROP 2 LAST $XR0 142 
J 0
(-8055 3150);
DISPLAY 0.638298 (-8055 3150);
PAINT MONO (-8055 3150);
FORCEPROP 1 LAST OFFPAGE TRUE
J 0
(-7475 3025);
DISPLAY 0.872340 (-7475 3025);
PAINT GREEN (-7475 3025);
DISPLAY INVISIBLE (-7475 3025);
FORCEPROP 1 LAST COMMENT_BODY TRUE
J 0
(-7700 3075);
DISPLAY 0.872340 (-7700 3075);
PAINT GREEN (-7700 3075);
DISPLAY INVISIBLE (-7700 3075);
FORCEPROP 2 LAST PATH I158
J 0
(-7750 3225);
DISPLAY 1.021277 (-7750 3225);
PAINT ORANGE (-7750 3225);
DISPLAY INVISIBLE (-7750 3225);
FORCEPROP 2 LAST CDS_LIB mstr_standard
J 0
(-7800 3150);
PAINT MONO (-7800 3150);
DISPLAY INVISIBLE (-7800 3150);
FORCEADD OFFPAGE..4
(-5050 3200);
FORCEPROP 2 LAST $XR0 114 
J 0
(-4864 3200);
DISPLAY 0.638298 (-4864 3200);
PAINT MONO (-4864 3200);
FORCEPROP 1 LAST COMMENT_BODY TRUE
J 0
(-5075 3100);
DISPLAY 0.872340 (-5075 3100);
PAINT GREEN (-5075 3100);
DISPLAY INVISIBLE (-5075 3100);
FORCEPROP 2 LAST CDS_LIB mstr_standard
J 0
(-5050 3200);
PAINT ORANGE (-5050 3200);
DISPLAY INVISIBLE (-5050 3200);
FORCEPROP 1 LAST OFFPAGE TRUE
J 0
(-4725 3075);
DISPLAY 0.872340 (-4725 3075);
PAINT GREEN (-4725 3075);
DISPLAY INVISIBLE (-4725 3075);
FORCEPROP 2 LAST PATH I159
J 0
(-4850 3250);
DISPLAY 1.021277 (-4850 3250);
PAINT ORANGE (-4850 3250);
DISPLAY INVISIBLE (-4850 3250);
FORCEADD OFFPAGE..4
(-5050 3150);
FORCEPROP 2 LAST $XR0 114 
J 0
(-4864 3150);
DISPLAY 0.638298 (-4864 3150);
PAINT MONO (-4864 3150);
FORCEPROP 2 LAST PATH I160
J 0
(-4850 3200);
DISPLAY 1.021277 (-4850 3200);
PAINT ORANGE (-4850 3200);
DISPLAY INVISIBLE (-4850 3200);
FORCEPROP 1 LAST OFFPAGE TRUE
J 0
(-4725 3025);
DISPLAY 0.872340 (-4725 3025);
PAINT GREEN (-4725 3025);
DISPLAY INVISIBLE (-4725 3025);
FORCEPROP 2 LAST CDS_LIB mstr_standard
J 0
(-5050 3150);
PAINT ORANGE (-5050 3150);
DISPLAY INVISIBLE (-5050 3150);
FORCEPROP 1 LAST COMMENT_BODY TRUE
J 0
(-5075 3050);
DISPLAY 0.872340 (-5075 3050);
PAINT GREEN (-5075 3050);
DISPLAY INVISIBLE (-5075 3050);
FORCEADD OFFPAGE..4
(-5050 3300);
FORCEPROP 2 LAST $XR0 185 
J 0
(-4864 3300);
DISPLAY 0.638298 (-4864 3300);
PAINT MONO (-4864 3300);
FORCEPROP 1 LAST OFFPAGE TRUE
J 0
(-4725 3175);
DISPLAY 0.872340 (-4725 3175);
PAINT GREEN (-4725 3175);
DISPLAY INVISIBLE (-4725 3175);
FORCEPROP 1 LAST COMMENT_BODY TRUE
J 0
(-5075 3200);
DISPLAY 0.872340 (-5075 3200);
PAINT GREEN (-5075 3200);
DISPLAY INVISIBLE (-5075 3200);
FORCEPROP 2 LAST PATH I161
J 0
(-4875 3375);
DISPLAY 1.021277 (-4875 3375);
PAINT ORANGE (-4875 3375);
DISPLAY INVISIBLE (-4875 3375);
FORCEPROP 2 LAST CDS_LIB mstr_standard
J 0
(-5050 3300);
PAINT MONO (-5050 3300);
DISPLAY INVISIBLE (-5050 3300);
FORCEADD OFFPAGE..4
(-5050 3350);
FORCEPROP 2 LAST $XR0 185 
J 0
(-4864 3350);
DISPLAY 0.638298 (-4864 3350);
PAINT MONO (-4864 3350);
FORCEPROP 1 LAST COMMENT_BODY TRUE
J 0
(-5075 3250);
DISPLAY 0.872340 (-5075 3250);
PAINT GREEN (-5075 3250);
DISPLAY INVISIBLE (-5075 3250);
FORCEPROP 1 LAST OFFPAGE TRUE
J 0
(-4725 3225);
DISPLAY 0.872340 (-4725 3225);
PAINT GREEN (-4725 3225);
DISPLAY INVISIBLE (-4725 3225);
FORCEPROP 2 LAST PATH I162
J 0
(-4875 3425);
DISPLAY 1.021277 (-4875 3425);
PAINT ORANGE (-4875 3425);
DISPLAY INVISIBLE (-4875 3425);
FORCEPROP 2 LAST CDS_LIB mstr_standard
J 0
(-5050 3350);
PAINT MONO (-5050 3350);
DISPLAY INVISIBLE (-5050 3350);
FORCEADD OFFPAGE..2
(-5050 3450);
FORCEPROP 2 LAST $XR0 185 
J 0
(-4861 3450);
DISPLAY 0.638298 (-4861 3450);
PAINT MONO (-4861 3450);
FORCEPROP 2 LAST CDS_LIB mstr_standard
J 0
(-5050 3450);
PAINT MONO (-5050 3450);
DISPLAY INVISIBLE (-5050 3450);
FORCEPROP 2 LAST PATH I163
J 0
(-4875 3525);
DISPLAY 1.021277 (-4875 3525);
PAINT ORANGE (-4875 3525);
DISPLAY INVISIBLE (-4875 3525);
FORCEPROP 1 LAST OFFPAGE TRUE
J 0
(-4725 3325);
DISPLAY 0.872340 (-4725 3325);
PAINT GREEN (-4725 3325);
DISPLAY INVISIBLE (-4725 3325);
FORCEPROP 1 LAST COMMENT_BODY TRUE
J 0
(-5095 3355);
DISPLAY 0.872340 (-5095 3355);
PAINT GREEN (-5095 3355);
DISPLAY INVISIBLE (-5095 3355);
FORCEADD OFFPAGE..2
(-5050 3500);
FORCEPROP 2 LAST $XR0 185 
J 0
(-4861 3500);
DISPLAY 0.638298 (-4861 3500);
PAINT MONO (-4861 3500);
FORCEPROP 2 LAST CDS_LIB mstr_standard
J 0
(-5050 3500);
PAINT MONO (-5050 3500);
DISPLAY INVISIBLE (-5050 3500);
FORCEPROP 2 LAST PATH I164
J 0
(-4875 3575);
DISPLAY 1.021277 (-4875 3575);
PAINT ORANGE (-4875 3575);
DISPLAY INVISIBLE (-4875 3575);
FORCEPROP 1 LAST OFFPAGE TRUE
J 0
(-4725 3375);
DISPLAY 0.872340 (-4725 3375);
PAINT GREEN (-4725 3375);
DISPLAY INVISIBLE (-4725 3375);
FORCEPROP 1 LAST COMMENT_BODY TRUE
J 0
(-5095 3405);
DISPLAY 0.872340 (-5095 3405);
PAINT GREEN (-5095 3405);
DISPLAY INVISIBLE (-5095 3405);
FORCEADD OFFPAGE..4
(-3500 3600);
FORCEPROP 2 LAST $XR0 116 
J 0
(-3314 3600);
DISPLAY 0.638298 (-3314 3600);
PAINT MONO (-3314 3600);
FORCEPROP 1 LAST COMMENT_BODY TRUE
J 0
(-3525 3500);
DISPLAY 0.872340 (-3525 3500);
PAINT GREEN (-3525 3500);
DISPLAY INVISIBLE (-3525 3500);
FORCEPROP 2 LAST CDS_LIB mstr_standard
J 0
(-3500 3600);
PAINT ORANGE (-3500 3600);
DISPLAY INVISIBLE (-3500 3600);
FORCEPROP 1 LAST OFFPAGE TRUE
J 0
(-3175 3475);
DISPLAY 0.872340 (-3175 3475);
PAINT GREEN (-3175 3475);
DISPLAY INVISIBLE (-3175 3475);
FORCEPROP 2 LAST PATH I165
J 0
(-3300 3650);
DISPLAY 1.021277 (-3300 3650);
PAINT ORANGE (-3300 3650);
DISPLAY INVISIBLE (-3300 3650);
FORCEADD OFFPAGE..4
(-3500 3650);
FORCEPROP 2 LAST $XR0 116 
J 0
(-3314 3650);
DISPLAY 0.638298 (-3314 3650);
PAINT MONO (-3314 3650);
FORCEPROP 1 LAST OFFPAGE TRUE
J 0
(-3175 3525);
DISPLAY 0.872340 (-3175 3525);
PAINT GREEN (-3175 3525);
DISPLAY INVISIBLE (-3175 3525);
FORCEPROP 2 LAST CDS_LIB mstr_standard
J 0
(-3500 3650);
PAINT ORANGE (-3500 3650);
DISPLAY INVISIBLE (-3500 3650);
FORCEPROP 1 LAST COMMENT_BODY TRUE
J 0
(-3525 3550);
DISPLAY 0.872340 (-3525 3550);
PAINT GREEN (-3525 3550);
DISPLAY INVISIBLE (-3525 3550);
FORCEPROP 2 LAST PATH I166
J 0
(-3300 3700);
DISPLAY 1.021277 (-3300 3700);
PAINT ORANGE (-3300 3700);
DISPLAY INVISIBLE (-3300 3700);
FORCEADD CAP..2
(-4850 3650);
FORCEPROP 1 LAST VALUE 0.22UF
J 2
(-5075 3650);
DISPLAY 0.617021 (-5075 3650);
PAINT SKYBLUE (-5075 3650);
FORCEPROP 1 LAST LOCATION C2T11
J 1
(-5325 3650);
DISPLAY 0.617021 (-5325 3650);
PAINT AQUA (-5325 3650);
FORCEPROP 1 LAST PACK_TYPE 0402
J 1
(-4425 3650);
DISPLAY 0.617021 (-4425 3650);
PAINT SKYBLUE (-4425 3650);
FORCEPROP 1 LAST VOLTAGE 16V
J 0
(-4575 3650);
DISPLAY 0.617021 (-4575 3650);
PAINT SKYBLUE (-4575 3650);
FORCEPROP 1 LAST MATERIAL X7R
J 0
(-4700 3650);
DISPLAY 0.617021 (-4700 3650);
PAINT SKYBLUE (-4700 3650);
FORCEPROP 1 LASTPIN (-4750 3650) $PN 2
J 0
(-4765 3665);
DISPLAY 0.617021 (-4765 3665);
PAINT ORANGE (-4765 3665);
FORCEPROP 1 LAST TOLERANCE 10%
J 2
(-4975 3650);
DISPLAY 0.617021 (-4975 3650);
PAINT SKYBLUE (-4975 3650);
FORCEPROP 1 LASTPIN (-4950 3650) $PN 1
J 0
(-4960 3665);
DISPLAY 0.617021 (-4960 3665);
PAINT ORANGE (-4960 3665);
FORCEPROP 1 LAST PART_NUMBER A36096-155
J 2
(-4125 3650);
DISPLAY 0.617021 (-4125 3650);
PAINT BLUE (-4125 3650);
FORCEPROP 0 LAST ROOM M_2
J 0
(-4125 3750);
DISPLAY 1.021277 (-4125 3750);
PAINT ORANGE (-4125 3750);
DISPLAY INVISIBLE (-4125 3750);
FORCEPROP 0 LAST BOM_COST ST_FLASH
J 0
(-4125 3850);
DISPLAY 1.021277 (-4125 3850);
PAINT ORANGE (-4125 3850);
DISPLAY INVISIBLE (-4125 3850);
FORCEPROP 2 LAST SEC 1
J 0
(-4850 3900);
DISPLAY 0.680851 (-4850 3900);
PAINT MONO (-4850 3900);
DISPLAY INVISIBLE (-4850 3900);
FORCEPROP 2 LAST SEC_TYPE 0402
J 0
(-4850 3900);
DISPLAY 1.021277 (-4850 3900);
PAINT ORANGE (-4850 3900);
DISPLAY INVISIBLE (-4850 3900);
FORCEPROP 2 LAST CDS_LIB mstr_discrete
J 0
(-4850 3650);
PAINT ORANGE (-4850 3650);
DISPLAY INVISIBLE (-4850 3650);
FORCEPROP 2 LAST CDS_LOCATION C2T11
J 1
(-5325 3650);
DISPLAY 0.617021 (-5325 3650);
PAINT AQUA (-5325 3650);
DISPLAY INVISIBLE (-5325 3650);
FORCEPROP 1 LAST PATH I167
J 0
(-4850 3850);
DISPLAY 0.978723 (-4850 3850);
PAINT WHITE (-4850 3850);
DISPLAY INVISIBLE (-4850 3850);
FORCEADD CAP..2
(-4850 3600);
FORCEPROP 1 LAST LOCATION C2T10
J 1
(-5325 3600);
DISPLAY 0.617021 (-5325 3600);
PAINT AQUA (-5325 3600);
FORCEPROP 1 LASTPIN (-4950 3600) $PN 1
J 0
(-4960 3615);
DISPLAY 0.617021 (-4960 3615);
PAINT ORANGE (-4960 3615);
FORCEPROP 1 LASTPIN (-4750 3600) $PN 2
J 0
(-4765 3615);
DISPLAY 0.617021 (-4765 3615);
PAINT ORANGE (-4765 3615);
FORCEPROP 1 LAST MATERIAL X7R
J 0
(-4700 3600);
DISPLAY 0.617021 (-4700 3600);
PAINT SKYBLUE (-4700 3600);
FORCEPROP 1 LAST PACK_TYPE 0402
J 1
(-4425 3600);
DISPLAY 0.617021 (-4425 3600);
PAINT SKYBLUE (-4425 3600);
FORCEPROP 1 LAST PART_NUMBER A36096-155
J 2
(-4125 3600);
DISPLAY 0.617021 (-4125 3600);
PAINT BLUE (-4125 3600);
FORCEPROP 1 LAST VOLTAGE 16V
J 0
(-4575 3600);
DISPLAY 0.617021 (-4575 3600);
PAINT SKYBLUE (-4575 3600);
FORCEPROP 1 LAST VALUE 0.22UF
J 2
(-5075 3600);
DISPLAY 0.617021 (-5075 3600);
PAINT SKYBLUE (-5075 3600);
FORCEPROP 1 LAST TOLERANCE 10%
J 2
(-4975 3600);
DISPLAY 0.617021 (-4975 3600);
PAINT SKYBLUE (-4975 3600);
FORCEPROP 2 LAST CDS_LOCATION C2T10
J 1
(-5325 3600);
DISPLAY 0.617021 (-5325 3600);
PAINT AQUA (-5325 3600);
DISPLAY INVISIBLE (-5325 3600);
FORCEPROP 2 LAST CDS_LIB mstr_discrete
J 0
(-4850 3600);
PAINT ORANGE (-4850 3600);
DISPLAY INVISIBLE (-4850 3600);
FORCEPROP 2 LAST SEC_TYPE 0402
J 0
(-4850 3850);
DISPLAY 1.021277 (-4850 3850);
PAINT ORANGE (-4850 3850);
DISPLAY INVISIBLE (-4850 3850);
FORCEPROP 2 LAST SEC 1
J 0
(-4850 3850);
DISPLAY 0.680851 (-4850 3850);
PAINT MONO (-4850 3850);
DISPLAY INVISIBLE (-4850 3850);
FORCEPROP 0 LAST BOM_COST ST_FLASH
J 0
(-4125 3700);
DISPLAY 1.021277 (-4125 3700);
PAINT ORANGE (-4125 3700);
DISPLAY INVISIBLE (-4125 3700);
FORCEPROP 0 LAST ROOM M_2
J 0
(-4125 3700);
DISPLAY 1.021277 (-4125 3700);
PAINT ORANGE (-4125 3700);
DISPLAY INVISIBLE (-4125 3700);
FORCEPROP 1 LAST PATH I168
J 0
(-4850 3800);
DISPLAY 0.978723 (-4850 3800);
PAINT WHITE (-4850 3800);
DISPLAY INVISIBLE (-4850 3800);
FORCEADD OFFPAGE..2
(-3500 3750);
FORCEPROP 2 LAST $XR0 116 
J 0
(-3311 3750);
DISPLAY 0.638298 (-3311 3750);
PAINT MONO (-3311 3750);
FORCEPROP 2 LAST PATH I169
J 0
(-3300 3800);
DISPLAY 1.021277 (-3300 3800);
PAINT ORANGE (-3300 3800);
DISPLAY INVISIBLE (-3300 3800);
FORCEPROP 1 LAST OFFPAGE TRUE
J 0
(-3175 3625);
DISPLAY 0.872340 (-3175 3625);
PAINT GREEN (-3175 3625);
DISPLAY INVISIBLE (-3175 3625);
FORCEPROP 2 LAST CDS_LIB mstr_standard
J 0
(-3500 3750);
PAINT ORANGE (-3500 3750);
DISPLAY INVISIBLE (-3500 3750);
FORCEPROP 1 LAST COMMENT_BODY TRUE
J 0
(-3545 3655);
DISPLAY 0.872340 (-3545 3655);
PAINT GREEN (-3545 3655);
DISPLAY INVISIBLE (-3545 3655);
FORCEADD OFFPAGE..2
(-3500 3800);
FORCEPROP 2 LAST $XR0 116 
J 0
(-3311 3800);
DISPLAY 0.638298 (-3311 3800);
PAINT MONO (-3311 3800);
FORCEPROP 2 LAST PATH I170
J 0
(-3300 3850);
DISPLAY 1.021277 (-3300 3850);
PAINT ORANGE (-3300 3850);
DISPLAY INVISIBLE (-3300 3850);
FORCEPROP 1 LAST OFFPAGE TRUE
J 0
(-3175 3675);
DISPLAY 0.872340 (-3175 3675);
PAINT GREEN (-3175 3675);
DISPLAY INVISIBLE (-3175 3675);
FORCEPROP 2 LAST CDS_LIB mstr_standard
J 0
(-3500 3800);
PAINT ORANGE (-3500 3800);
DISPLAY INVISIBLE (-3500 3800);
FORCEPROP 1 LAST COMMENT_BODY TRUE
J 0
(-3545 3705);
DISPLAY 0.872340 (-3545 3705);
PAINT GREEN (-3545 3705);
DISPLAY INVISIBLE (-3545 3705);
FORCEADD CAP..2
(-4850 3950);
FORCEPROP 1 LAST PART_NUMBER A36096-155
J 2
(-4125 3950);
DISPLAY 0.617021 (-4125 3950);
PAINT BLUE (-4125 3950);
FORCEPROP 1 LAST PACK_TYPE 0402
J 1
(-4425 3950);
DISPLAY 0.617021 (-4425 3950);
PAINT SKYBLUE (-4425 3950);
FORCEPROP 1 LAST LOCATION C2T14
J 1
(-5325 3950);
DISPLAY 0.617021 (-5325 3950);
PAINT AQUA (-5325 3950);
FORCEPROP 1 LAST VOLTAGE 16V
J 0
(-4575 3950);
DISPLAY 0.617021 (-4575 3950);
PAINT SKYBLUE (-4575 3950);
FORCEPROP 1 LAST MATERIAL X7R
J 0
(-4700 3950);
DISPLAY 0.617021 (-4700 3950);
PAINT SKYBLUE (-4700 3950);
FORCEPROP 1 LASTPIN (-4750 3950) $PN 2
J 0
(-4765 3965);
DISPLAY 0.617021 (-4765 3965);
PAINT ORANGE (-4765 3965);
FORCEPROP 1 LASTPIN (-4950 3950) $PN 1
J 0
(-4960 3965);
DISPLAY 0.617021 (-4960 3965);
PAINT ORANGE (-4960 3965);
FORCEPROP 1 LAST TOLERANCE 10%
J 2
(-4975 3950);
DISPLAY 0.617021 (-4975 3950);
PAINT SKYBLUE (-4975 3950);
FORCEPROP 1 LAST VALUE 0.22UF
J 2
(-5075 3950);
DISPLAY 0.617021 (-5075 3950);
PAINT SKYBLUE (-5075 3950);
FORCEPROP 1 LAST PATH I171
J 0
(-4850 4150);
DISPLAY 0.978723 (-4850 4150);
PAINT WHITE (-4850 4150);
DISPLAY INVISIBLE (-4850 4150);
FORCEPROP 0 LAST CDS_SEC 1
J 0
(-4125 4000);
PAINT MONO (-4125 4000);
DISPLAY INVISIBLE (-4125 4000);
FORCEPROP 2 LAST SEC 1
J 0
(-4850 4200);
DISPLAY 0.680851 (-4850 4200);
PAINT MONO (-4850 4200);
DISPLAY INVISIBLE (-4850 4200);
FORCEPROP 2 LAST SEC_TYPE 0402
J 0
(-4850 4200);
DISPLAY 1.021277 (-4850 4200);
PAINT ORANGE (-4850 4200);
DISPLAY INVISIBLE (-4850 4200);
FORCEPROP 0 LAST ROOM M_2
J 0
(-4125 4000);
DISPLAY 1.021277 (-4125 4000);
PAINT ORANGE (-4125 4000);
DISPLAY INVISIBLE (-4125 4000);
FORCEPROP 0 LAST BOM_COST ST_FLASH
J 0
(-4125 4050);
DISPLAY 1.021277 (-4125 4050);
PAINT ORANGE (-4125 4050);
DISPLAY INVISIBLE (-4125 4050);
FORCEPROP 2 LAST CDS_LIB mstr_discrete
J 0
(-4850 3950);
PAINT ORANGE (-4850 3950);
DISPLAY INVISIBLE (-4850 3950);
FORCEPROP 2 LAST CDS_LOCATION C2T14
J 1
(-5325 3950);
DISPLAY 0.617021 (-5325 3950);
PAINT AQUA (-5325 3950);
DISPLAY INVISIBLE (-5325 3950);
FORCEADD CAP..2
(-4850 3900);
FORCEPROP 1 LAST VOLTAGE 16V
J 0
(-4575 3900);
DISPLAY 0.617021 (-4575 3900);
PAINT SKYBLUE (-4575 3900);
FORCEPROP 1 LAST LOCATION C2T13
J 1
(-5325 3900);
DISPLAY 0.617021 (-5325 3900);
PAINT AQUA (-5325 3900);
FORCEPROP 1 LAST TOLERANCE 10%
J 2
(-4975 3900);
DISPLAY 0.617021 (-4975 3900);
PAINT SKYBLUE (-4975 3900);
FORCEPROP 1 LASTPIN (-4750 3900) $PN 2
J 0
(-4765 3915);
DISPLAY 0.617021 (-4765 3915);
PAINT ORANGE (-4765 3915);
FORCEPROP 1 LAST MATERIAL X7R
J 0
(-4700 3900);
DISPLAY 0.617021 (-4700 3900);
PAINT SKYBLUE (-4700 3900);
FORCEPROP 1 LAST PACK_TYPE 0402
J 1
(-4425 3900);
DISPLAY 0.617021 (-4425 3900);
PAINT SKYBLUE (-4425 3900);
FORCEPROP 1 LAST PART_NUMBER A36096-155
J 2
(-4125 3900);
DISPLAY 0.617021 (-4125 3900);
PAINT BLUE (-4125 3900);
FORCEPROP 1 LASTPIN (-4950 3900) $PN 1
J 0
(-4960 3915);
DISPLAY 0.617021 (-4960 3915);
PAINT ORANGE (-4960 3915);
FORCEPROP 1 LAST VALUE 0.22UF
J 2
(-5075 3900);
DISPLAY 0.617021 (-5075 3900);
PAINT SKYBLUE (-5075 3900);
FORCEPROP 2 LAST CDS_LOCATION C2T13
J 1
(-5325 3900);
DISPLAY 0.617021 (-5325 3900);
PAINT AQUA (-5325 3900);
DISPLAY INVISIBLE (-5325 3900);
FORCEPROP 2 LAST CDS_LIB mstr_discrete
J 0
(-4850 3900);
PAINT ORANGE (-4850 3900);
DISPLAY INVISIBLE (-4850 3900);
FORCEPROP 0 LAST BOM_COST ST_FLASH
J 0
(-4125 4000);
DISPLAY 1.021277 (-4125 4000);
PAINT ORANGE (-4125 4000);
DISPLAY INVISIBLE (-4125 4000);
FORCEPROP 0 LAST ROOM M_2
J 0
(-4125 3950);
DISPLAY 1.021277 (-4125 3950);
PAINT ORANGE (-4125 3950);
DISPLAY INVISIBLE (-4125 3950);
FORCEPROP 2 LAST SEC_TYPE 0402
J 0
(-4850 4150);
DISPLAY 1.021277 (-4850 4150);
PAINT ORANGE (-4850 4150);
DISPLAY INVISIBLE (-4850 4150);
FORCEPROP 2 LAST SEC 1
J 0
(-4850 4150);
DISPLAY 0.680851 (-4850 4150);
PAINT MONO (-4850 4150);
DISPLAY INVISIBLE (-4850 4150);
FORCEPROP 0 LAST CDS_SEC 1
J 0
(-4125 3950);
PAINT MONO (-4125 3950);
DISPLAY INVISIBLE (-4125 3950);
FORCEPROP 1 LAST PATH I172
J 0
(-4850 4100);
DISPLAY 0.978723 (-4850 4100);
PAINT WHITE (-4850 4100);
DISPLAY INVISIBLE (-4850 4100);
FORCEADD OFFPAGE..4
(-3500 3900);
FORCEPROP 2 LAST $XR0 116 
J 0
(-3314 3900);
DISPLAY 0.638298 (-3314 3900);
PAINT MONO (-3314 3900);
FORCEPROP 1 LAST COMMENT_BODY TRUE
J 0
(-3525 3800);
DISPLAY 0.872340 (-3525 3800);
PAINT GREEN (-3525 3800);
DISPLAY INVISIBLE (-3525 3800);
FORCEPROP 2 LAST CDS_LIB mstr_standard
J 0
(-3500 3900);
PAINT ORANGE (-3500 3900);
DISPLAY INVISIBLE (-3500 3900);
FORCEPROP 1 LAST OFFPAGE TRUE
J 0
(-3175 3775);
DISPLAY 0.872340 (-3175 3775);
PAINT GREEN (-3175 3775);
DISPLAY INVISIBLE (-3175 3775);
FORCEPROP 2 LAST PATH I173
J 0
(-3300 3950);
DISPLAY 1.021277 (-3300 3950);
PAINT ORANGE (-3300 3950);
DISPLAY INVISIBLE (-3300 3950);
FORCEADD OFFPAGE..4
(-3500 3950);
FORCEPROP 2 LAST $XR0 116 
J 0
(-3314 3950);
DISPLAY 0.638298 (-3314 3950);
PAINT MONO (-3314 3950);
FORCEPROP 2 LAST PATH I174
J 0
(-3300 4000);
DISPLAY 1.021277 (-3300 4000);
PAINT ORANGE (-3300 4000);
DISPLAY INVISIBLE (-3300 4000);
FORCEPROP 1 LAST OFFPAGE TRUE
J 0
(-3175 3825);
DISPLAY 0.872340 (-3175 3825);
PAINT GREEN (-3175 3825);
DISPLAY INVISIBLE (-3175 3825);
FORCEPROP 2 LAST CDS_LIB mstr_standard
J 0
(-3500 3950);
PAINT ORANGE (-3500 3950);
DISPLAY INVISIBLE (-3500 3950);
FORCEPROP 1 LAST COMMENT_BODY TRUE
J 0
(-3525 3850);
DISPLAY 0.872340 (-3525 3850);
PAINT GREEN (-3525 3850);
DISPLAY INVISIBLE (-3525 3850);
FORCEADD OFFPAGE..2
(-3500 4050);
FORCEPROP 2 LAST $XR0 116 
J 0
(-3311 4050);
DISPLAY 0.638298 (-3311 4050);
PAINT MONO (-3311 4050);
FORCEPROP 2 LAST PATH I175
J 0
(-3300 4100);
DISPLAY 1.021277 (-3300 4100);
PAINT ORANGE (-3300 4100);
DISPLAY INVISIBLE (-3300 4100);
FORCEPROP 1 LAST OFFPAGE TRUE
J 0
(-3175 3925);
DISPLAY 0.872340 (-3175 3925);
PAINT GREEN (-3175 3925);
DISPLAY INVISIBLE (-3175 3925);
FORCEPROP 2 LAST CDS_LIB mstr_standard
J 0
(-3500 4050);
PAINT ORANGE (-3500 4050);
DISPLAY INVISIBLE (-3500 4050);
FORCEPROP 1 LAST COMMENT_BODY TRUE
J 0
(-3545 3955);
DISPLAY 0.872340 (-3545 3955);
PAINT GREEN (-3545 3955);
DISPLAY INVISIBLE (-3545 3955);
FORCEADD OFFPAGE..2
(-3500 4100);
FORCEPROP 2 LAST $XR0 116 
J 0
(-3311 4100);
DISPLAY 0.638298 (-3311 4100);
PAINT MONO (-3311 4100);
FORCEPROP 2 LAST PATH I176
J 0
(-3300 4150);
DISPLAY 1.021277 (-3300 4150);
PAINT ORANGE (-3300 4150);
DISPLAY INVISIBLE (-3300 4150);
FORCEPROP 1 LAST OFFPAGE TRUE
J 0
(-3175 3975);
DISPLAY 0.872340 (-3175 3975);
PAINT GREEN (-3175 3975);
DISPLAY INVISIBLE (-3175 3975);
FORCEPROP 2 LAST CDS_LIB mstr_standard
J 0
(-3500 4100);
PAINT ORANGE (-3500 4100);
DISPLAY INVISIBLE (-3500 4100);
FORCEPROP 1 LAST COMMENT_BODY TRUE
J 0
(-3545 4005);
DISPLAY 0.872340 (-3545 4005);
PAINT GREEN (-3545 4005);
DISPLAY INVISIBLE (-3545 4005);
FORCEADD OFFPAGE..4
(-3500 4200);
FORCEPROP 2 LAST $XR0 116 
J 0
(-3314 4200);
DISPLAY 0.638298 (-3314 4200);
PAINT MONO (-3314 4200);
FORCEPROP 1 LAST OFFPAGE TRUE
J 0
(-3175 4075);
DISPLAY 0.872340 (-3175 4075);
PAINT GREEN (-3175 4075);
DISPLAY INVISIBLE (-3175 4075);
FORCEPROP 1 LAST COMMENT_BODY TRUE
J 0
(-3525 4100);
DISPLAY 0.872340 (-3525 4100);
PAINT GREEN (-3525 4100);
DISPLAY INVISIBLE (-3525 4100);
FORCEPROP 2 LAST CDS_LIB mstr_standard
J 0
(-3500 4200);
PAINT ORANGE (-3500 4200);
DISPLAY INVISIBLE (-3500 4200);
FORCEPROP 2 LAST PATH I177
J 0
(-3300 4250);
DISPLAY 1.021277 (-3300 4250);
PAINT ORANGE (-3300 4250);
DISPLAY INVISIBLE (-3300 4250);
FORCEADD OFFPAGE..4
(-3500 4250);
FORCEPROP 2 LAST $XR0 116 
J 0
(-3314 4250);
DISPLAY 0.638298 (-3314 4250);
PAINT MONO (-3314 4250);
FORCEPROP 2 LAST PATH I178
J 0
(-3300 4300);
DISPLAY 1.021277 (-3300 4300);
PAINT ORANGE (-3300 4300);
DISPLAY INVISIBLE (-3300 4300);
FORCEPROP 2 LAST CDS_LIB mstr_standard
J 0
(-3500 4250);
PAINT ORANGE (-3500 4250);
DISPLAY INVISIBLE (-3500 4250);
FORCEPROP 1 LAST OFFPAGE TRUE
J 0
(-3175 4125);
DISPLAY 0.872340 (-3175 4125);
PAINT GREEN (-3175 4125);
DISPLAY INVISIBLE (-3175 4125);
FORCEPROP 1 LAST COMMENT_BODY TRUE
J 0
(-3525 4150);
DISPLAY 0.872340 (-3525 4150);
PAINT GREEN (-3525 4150);
DISPLAY INVISIBLE (-3525 4150);
FORCEADD CAP..2
(-4850 4200);
FORCEPROP 1 LAST PART_NUMBER A36096-155
J 2
(-4125 4200);
DISPLAY 0.617021 (-4125 4200);
PAINT BLUE (-4125 4200);
FORCEPROP 1 LAST TOLERANCE 10%
J 2
(-4975 4200);
DISPLAY 0.617021 (-4975 4200);
PAINT SKYBLUE (-4975 4200);
FORCEPROP 1 LASTPIN (-4950 4200) $PN 1
J 0
(-4960 4215);
DISPLAY 0.617021 (-4960 4215);
PAINT ORANGE (-4960 4215);
FORCEPROP 1 LASTPIN (-4750 4200) $PN 2
J 0
(-4765 4215);
DISPLAY 0.617021 (-4765 4215);
PAINT ORANGE (-4765 4215);
FORCEPROP 1 LAST MATERIAL X7R
J 0
(-4700 4200);
DISPLAY 0.617021 (-4700 4200);
PAINT SKYBLUE (-4700 4200);
FORCEPROP 1 LAST VOLTAGE 16V
J 0
(-4575 4200);
DISPLAY 0.617021 (-4575 4200);
PAINT SKYBLUE (-4575 4200);
FORCEPROP 1 LAST PACK_TYPE 0402
J 1
(-4425 4200);
DISPLAY 0.617021 (-4425 4200);
PAINT SKYBLUE (-4425 4200);
FORCEPROP 1 LAST LOCATION C2T20
J 1
(-5325 4200);
DISPLAY 0.617021 (-5325 4200);
PAINT AQUA (-5325 4200);
FORCEPROP 1 LAST VALUE 0.22UF
J 2
(-5075 4200);
DISPLAY 0.617021 (-5075 4200);
PAINT SKYBLUE (-5075 4200);
FORCEPROP 2 LAST CDS_LOCATION C2T20
J 1
(-5325 4200);
DISPLAY 0.617021 (-5325 4200);
PAINT AQUA (-5325 4200);
DISPLAY INVISIBLE (-5325 4200);
FORCEPROP 2 LAST CDS_LIB mstr_discrete
J 0
(-4850 4200);
PAINT ORANGE (-4850 4200);
DISPLAY INVISIBLE (-4850 4200);
FORCEPROP 2 LAST SEC_TYPE 0402
J 0
(-4850 4450);
DISPLAY 1.021277 (-4850 4450);
PAINT ORANGE (-4850 4450);
DISPLAY INVISIBLE (-4850 4450);
FORCEPROP 2 LAST SEC 1
J 0
(-4850 4450);
DISPLAY 0.680851 (-4850 4450);
PAINT MONO (-4850 4450);
DISPLAY INVISIBLE (-4850 4450);
FORCEPROP 0 LAST ROOM M_2
J 0
(-4125 4250);
DISPLAY 1.021277 (-4125 4250);
PAINT ORANGE (-4125 4250);
DISPLAY INVISIBLE (-4125 4250);
FORCEPROP 0 LAST BOM_COST ST_FLASH
J 0
(-4125 4300);
DISPLAY 1.021277 (-4125 4300);
PAINT ORANGE (-4125 4300);
DISPLAY INVISIBLE (-4125 4300);
FORCEPROP 0 LAST CDS_SEC 1
J 0
(-4125 4250);
PAINT MONO (-4125 4250);
DISPLAY INVISIBLE (-4125 4250);
FORCEPROP 1 LAST PATH I179
J 0
(-4850 4400);
DISPLAY 0.978723 (-4850 4400);
PAINT WHITE (-4850 4400);
DISPLAY INVISIBLE (-4850 4400);
FORCEADD CAP..2
(-4850 4250);
FORCEPROP 1 LAST PART_NUMBER A36096-155
J 2
(-4125 4250);
DISPLAY 0.617021 (-4125 4250);
PAINT BLUE (-4125 4250);
FORCEPROP 1 LAST PACK_TYPE 0402
J 1
(-4425 4250);
DISPLAY 0.617021 (-4425 4250);
PAINT SKYBLUE (-4425 4250);
FORCEPROP 1 LAST VOLTAGE 16V
J 0
(-4575 4250);
DISPLAY 0.617021 (-4575 4250);
PAINT SKYBLUE (-4575 4250);
FORCEPROP 1 LAST MATERIAL X7R
J 0
(-4700 4250);
DISPLAY 0.617021 (-4700 4250);
PAINT SKYBLUE (-4700 4250);
FORCEPROP 1 LASTPIN (-4750 4250) $PN 2
J 0
(-4765 4265);
DISPLAY 0.617021 (-4765 4265);
PAINT ORANGE (-4765 4265);
FORCEPROP 1 LASTPIN (-4950 4250) $PN 1
J 0
(-4960 4265);
DISPLAY 0.617021 (-4960 4265);
PAINT ORANGE (-4960 4265);
FORCEPROP 1 LAST TOLERANCE 10%
J 2
(-4975 4250);
DISPLAY 0.617021 (-4975 4250);
PAINT SKYBLUE (-4975 4250);
FORCEPROP 1 LAST VALUE 0.22UF
J 2
(-5075 4250);
DISPLAY 0.617021 (-5075 4250);
PAINT SKYBLUE (-5075 4250);
FORCEPROP 1 LAST LOCATION C2T23
J 1
(-5325 4250);
DISPLAY 0.617021 (-5325 4250);
PAINT AQUA (-5325 4250);
FORCEPROP 1 LAST PATH I180
J 0
(-4850 4450);
DISPLAY 0.978723 (-4850 4450);
PAINT WHITE (-4850 4450);
DISPLAY INVISIBLE (-4850 4450);
FORCEPROP 0 LAST CDS_SEC 1
J 0
(-4125 4300);
PAINT MONO (-4125 4300);
DISPLAY INVISIBLE (-4125 4300);
FORCEPROP 0 LAST BOM_COST ST_FLASH
J 0
(-4125 4350);
DISPLAY 1.021277 (-4125 4350);
PAINT ORANGE (-4125 4350);
DISPLAY INVISIBLE (-4125 4350);
FORCEPROP 0 LAST ROOM M_2
J 0
(-4125 4300);
DISPLAY 1.021277 (-4125 4300);
PAINT ORANGE (-4125 4300);
DISPLAY INVISIBLE (-4125 4300);
FORCEPROP 2 LAST SEC_TYPE 0402
J 0
(-4850 4500);
DISPLAY 1.021277 (-4850 4500);
PAINT ORANGE (-4850 4500);
DISPLAY INVISIBLE (-4850 4500);
FORCEPROP 2 LAST SEC 1
J 0
(-4850 4500);
DISPLAY 0.680851 (-4850 4500);
PAINT MONO (-4850 4500);
DISPLAY INVISIBLE (-4850 4500);
FORCEPROP 2 LAST CDS_LIB mstr_discrete
J 0
(-4850 4250);
PAINT ORANGE (-4850 4250);
DISPLAY INVISIBLE (-4850 4250);
FORCEPROP 2 LAST CDS_LOCATION C2T23
J 1
(-5325 4250);
DISPLAY 0.617021 (-5325 4250);
PAINT AQUA (-5325 4250);
DISPLAY INVISIBLE (-5325 4250);
FORCEADD OFFPAGE..2
(-5400 4350);
FORCEPROP 2 LAST $XR0 116 
J 0
(-5211 4350);
DISPLAY 0.638298 (-5211 4350);
PAINT MONO (-5211 4350);
FORCEPROP 2 LAST PATH I181
J 0
(-5200 4400);
DISPLAY 1.021277 (-5200 4400);
PAINT ORANGE (-5200 4400);
DISPLAY INVISIBLE (-5200 4400);
FORCEPROP 1 LAST OFFPAGE TRUE
J 0
(-5075 4225);
DISPLAY 0.872340 (-5075 4225);
PAINT GREEN (-5075 4225);
DISPLAY INVISIBLE (-5075 4225);
FORCEPROP 2 LAST CDS_LIB mstr_standard
J 0
(-5400 4350);
PAINT ORANGE (-5400 4350);
DISPLAY INVISIBLE (-5400 4350);
FORCEPROP 1 LAST COMMENT_BODY TRUE
J 0
(-5445 4255);
DISPLAY 0.872340 (-5445 4255);
PAINT GREEN (-5445 4255);
DISPLAY INVISIBLE (-5445 4255);
FORCEADD OFFPAGE..2
(-5400 4400);
FORCEPROP 2 LAST $XR0 116 
J 0
(-5211 4400);
DISPLAY 0.638298 (-5211 4400);
PAINT MONO (-5211 4400);
FORCEPROP 2 LAST PATH I182
J 0
(-5200 4450);
DISPLAY 1.021277 (-5200 4450);
PAINT ORANGE (-5200 4450);
DISPLAY INVISIBLE (-5200 4450);
FORCEPROP 1 LAST OFFPAGE TRUE
J 0
(-5075 4275);
DISPLAY 0.872340 (-5075 4275);
PAINT GREEN (-5075 4275);
DISPLAY INVISIBLE (-5075 4275);
FORCEPROP 2 LAST CDS_LIB mstr_standard
J 0
(-5400 4400);
PAINT ORANGE (-5400 4400);
DISPLAY INVISIBLE (-5400 4400);
FORCEPROP 1 LAST COMMENT_BODY TRUE
J 0
(-5445 4305);
DISPLAY 0.872340 (-5445 4305);
PAINT GREEN (-5445 4305);
DISPLAY INVISIBLE (-5445 4305);
FORCEADD RES..1
(-2850 2925);
FORCEPROP 1 LASTPIN (-2750 2925) $PN 2
J 0
(-2788 2937);
DISPLAY 0.617021 (-2788 2937);
PAINT ORANGE (-2788 2937);
FORCEPROP 1 LAST VALUE 0.0
J 0
(-2950 2775);
DISPLAY 0.617021 (-2950 2775);
PAINT SKYBLUE (-2950 2775);
FORCEPROP 1 LASTPIN (-2950 2925) $PN 1
J 0
(-2938 2937);
DISPLAY 0.617021 (-2938 2937);
PAINT ORANGE (-2938 2937);
FORCEPROP 1 LAST PACK_TYPE 0402
J 0
(-2950 2625);
DISPLAY 0.617021 (-2950 2625);
PAINT SKYBLUE (-2950 2625);
FORCEPROP 1 LAST MATERIAL CHIP
J 0
(-2950 2525);
DISPLAY 0.617021 (-2950 2525);
PAINT SKYBLUE (-2950 2525);
FORCEPROP 1 LAST PART_NUMBER G21497-005
J 0
(-2950 2575);
DISPLAY 0.617021 (-2950 2575);
PAINT BLUE (-2950 2575);
FORCEPROP 1 LAST WATTAGE 1/16W
J 0
(-2950 2675);
DISPLAY 0.617021 (-2950 2675);
PAINT SKYBLUE (-2950 2675);
FORCEPROP 1 LAST TOLERANCE 5%
J 0
(-2950 2725);
DISPLAY 0.617021 (-2950 2725);
PAINT SKYBLUE (-2950 2725);
FORCEPROP 1 LAST LOCATION R32W10
J 0
(-2950 2825);
DISPLAY 0.617021 (-2950 2825);
PAINT AQUA (-2950 2825);
FORCEPROP 1 LAST PATH I183
J 0
(-2900 3075);
DISPLAY 0.978723 (-2900 3075);
PAINT WHITE (-2900 3075);
DISPLAY INVISIBLE (-2900 3075);
FORCEPROP 0 LAST CDS_SEC 1
J 0
(-2575 3050);
DISPLAY INVISIBLE (-2575 3050);
FORCEPROP 0 LAST ROOM IO_SLOT
J 0
(-2800 3025);
DISPLAY 1.021277 (-2800 3025);
PAINT ORANGE (-2800 3025);
DISPLAY INVISIBLE (-2800 3025);
FORCEPROP 2 LAST SEC 1
J 0
(-2900 3125);
DISPLAY 0.680851 (-2900 3125);
PAINT MONO (-2900 3125);
DISPLAY INVISIBLE (-2900 3125);
FORCEPROP 2 LAST CDS_LIB mstr_discrete
J 0
(-2850 2925);
PAINT ORANGE (-2850 2925);
DISPLAY INVISIBLE (-2850 2925);
FORCEPROP 2 LAST SEC_TYPE 0402
J 0
(-2900 3125);
DISPLAY 1.021277 (-2900 3125);
PAINT ORANGE (-2900 3125);
DISPLAY INVISIBLE (-2900 3125);
FORCEPROP 2 LAST CDS_LOCATION R32W10
J 0
(-2725 2925);
DISPLAY 0.617021 (-2725 2925);
PAINT AQUA (-2725 2925);
DISPLAY INVISIBLE (-2725 2925);
FORCEADD RES..1
(-2625 2875);
FORCEPROP 1 LAST MATERIAL CHIP
J 0
(-2725 2525);
DISPLAY 0.617021 (-2725 2525);
PAINT SKYBLUE (-2725 2525);
FORCEPROP 1 LAST PART_NUMBER G21497-005
J 0
(-2725 2575);
DISPLAY 0.617021 (-2725 2575);
PAINT BLUE (-2725 2575);
FORCEPROP 1 LAST VALUE 0.0
J 0
(-2725 2775);
DISPLAY 0.617021 (-2725 2775);
PAINT SKYBLUE (-2725 2775);
FORCEPROP 1 LAST TOLERANCE 5%
J 0
(-2725 2725);
DISPLAY 0.617021 (-2725 2725);
PAINT SKYBLUE (-2725 2725);
FORCEPROP 1 LAST WATTAGE 1/16W
J 0
(-2725 2675);
DISPLAY 0.617021 (-2725 2675);
PAINT SKYBLUE (-2725 2675);
FORCEPROP 1 LAST PACK_TYPE 0402
J 0
(-2725 2625);
DISPLAY 0.617021 (-2725 2625);
PAINT SKYBLUE (-2725 2625);
FORCEPROP 1 LASTPIN (-2525 2875) $PN 2
J 0
(-2563 2887);
DISPLAY 0.617021 (-2563 2887);
PAINT ORANGE (-2563 2887);
FORCEPROP 1 LASTPIN (-2725 2875) $PN 1
J 0
(-2713 2887);
DISPLAY 0.617021 (-2713 2887);
PAINT ORANGE (-2713 2887);
FORCEPROP 1 LAST LOCATION R32W11
J 0
(-2725 2825);
DISPLAY 0.617021 (-2725 2825);
PAINT AQUA (-2725 2825);
FORCEPROP 1 LAST PATH I184
J 0
(-2675 3025);
DISPLAY 0.978723 (-2675 3025);
PAINT WHITE (-2675 3025);
DISPLAY INVISIBLE (-2675 3025);
FORCEPROP 2 LAST SEC_TYPE 0402
J 0
(-2675 3075);
DISPLAY 1.021277 (-2675 3075);
PAINT ORANGE (-2675 3075);
DISPLAY INVISIBLE (-2675 3075);
FORCEPROP 2 LAST CDS_LIB mstr_discrete
J 0
(-2625 2875);
PAINT ORANGE (-2625 2875);
DISPLAY INVISIBLE (-2625 2875);
FORCEPROP 2 LAST SEC 1
J 0
(-2675 3075);
DISPLAY 0.680851 (-2675 3075);
PAINT MONO (-2675 3075);
DISPLAY INVISIBLE (-2675 3075);
FORCEPROP 0 LAST ROOM IO_SLOT
J 0
(-2575 2975);
DISPLAY 1.021277 (-2575 2975);
PAINT ORANGE (-2575 2975);
DISPLAY INVISIBLE (-2575 2975);
FORCEPROP 0 LAST CDS_SEC 1
J 0
(-2350 3000);
DISPLAY INVISIBLE (-2350 3000);
FORCEPROP 2 LAST CDS_LOCATION R32W11
J 0
(-2500 2875);
DISPLAY 0.617021 (-2500 2875);
PAINT AQUA (-2500 2875);
DISPLAY INVISIBLE (-2500 2875);
FORCEADD GND..1
(-2450 3000);
FORCEPROP 3 LASTPIN (-2450 3050) SIG_NAME GND\g
J 0
(-2440 3060);
DISPLAY 0.659574 (-2440 3060);
PAINT MONO (-2440 3060);
DISPLAY INVISIBLE (-2440 3060);
FORCEPROP 1 LAST PATH I185
J 0
(-2375 3000);
DISPLAY 0.872340 (-2375 3000);
PAINT AQUA (-2375 3000);
DISPLAY INVISIBLE (-2375 3000);
FORCEPROP 2 LAST ROOM P2V5_LAN_AUX_VR
J 0
(-2750 3075);
DISPLAY 0.617021 (-2750 3075);
PAINT ORANGE (-2750 3075);
DISPLAY INVISIBLE (-2750 3075);
FORCEPROP 2 LAST BOM_COST NT_BASE_VRD
J 0
(-2750 3075);
DISPLAY 0.617021 (-2750 3075);
PAINT ORANGE (-2750 3075);
DISPLAY INVISIBLE (-2750 3075);
FORCEPROP 1 LAST SIZE 1B
J 0
(-2375 2950);
DISPLAY 0.872340 (-2375 2950);
PAINT GREEN (-2375 2950);
DISPLAY INVISIBLE (-2375 2950);
FORCEPROP 2 LAST CDS_LIB mstr_symbols
J 0
(-2450 3000);
PAINT MONO (-2450 3000);
DISPLAY INVISIBLE (-2450 3000);
FORCEPROP 1 LAST VOLTAGE 0
J 0
(-2450 3000);
PAINT SKYBLUE (-2450 3000);
DISPLAY INVISIBLE (-2450 3000);
FORCEPROP 1 LAST BODY_TYPE PLUMBING
J 0
(-2495 2957);
DISPLAY 0.340426 (-2495 2957);
PAINT GREEN (-2495 2957);
DISPLAY INVISIBLE (-2495 2957);
FORCEPROP 1 LAST HDL_POWER GND
J 0
(-2450 3150);
DISPLAY 0.872340 (-2450 3150);
PAINT GREEN (-2450 3150);
DISPLAY INVISIBLE (-2450 3150);
FORCEADD GND..1
(-2100 2725);
FORCEPROP 3 LASTPIN (-2100 2775) SIG_NAME GND\g
J 0
(-2090 2785);
DISPLAY 0.659574 (-2090 2785);
PAINT MONO (-2090 2785);
DISPLAY INVISIBLE (-2090 2785);
FORCEPROP 1 LAST PATH I186
J 0
(-2025 2725);
DISPLAY 0.872340 (-2025 2725);
PAINT AQUA (-2025 2725);
DISPLAY INVISIBLE (-2025 2725);
FORCEPROP 2 LAST ROOM P2V5_LAN_AUX_VR
J 0
(-2400 2800);
DISPLAY 0.617021 (-2400 2800);
PAINT ORANGE (-2400 2800);
DISPLAY INVISIBLE (-2400 2800);
FORCEPROP 2 LAST BOM_COST NT_BASE_VRD
J 0
(-2400 2800);
DISPLAY 0.617021 (-2400 2800);
PAINT ORANGE (-2400 2800);
DISPLAY INVISIBLE (-2400 2800);
FORCEPROP 1 LAST SIZE 1B
J 0
(-2025 2675);
DISPLAY 0.872340 (-2025 2675);
PAINT GREEN (-2025 2675);
DISPLAY INVISIBLE (-2025 2675);
FORCEPROP 2 LAST CDS_LIB mstr_symbols
J 0
(-2100 2725);
PAINT MONO (-2100 2725);
DISPLAY INVISIBLE (-2100 2725);
FORCEPROP 1 LAST VOLTAGE 0
J 0
(-2100 2725);
PAINT SKYBLUE (-2100 2725);
DISPLAY INVISIBLE (-2100 2725);
FORCEPROP 1 LAST BODY_TYPE PLUMBING
J 0
(-2145 2682);
DISPLAY 0.340426 (-2145 2682);
PAINT GREEN (-2145 2682);
DISPLAY INVISIBLE (-2145 2682);
FORCEPROP 1 LAST HDL_POWER GND
J 0
(-2100 2875);
DISPLAY 0.872340 (-2100 2875);
PAINT GREEN (-2100 2875);
DISPLAY INVISIBLE (-2100 2875);
FORCEADD RES..1
(-2675 3700);
FORCEPROP 1 LAST MATERIAL CHIP
J 0
(-2775 3350);
DISPLAY 0.617021 (-2775 3350);
PAINT SKYBLUE (-2775 3350);
FORCEPROP 1 LAST LOCATION R32W12
J 0
(-2775 3650);
DISPLAY 0.617021 (-2775 3650);
PAINT AQUA (-2775 3650);
FORCEPROP 1 LASTPIN (-2775 3700) $PN 1
J 0
(-2763 3712);
DISPLAY 0.617021 (-2763 3712);
PAINT ORANGE (-2763 3712);
FORCEPROP 1 LAST VALUE 0.0
J 0
(-2775 3600);
DISPLAY 0.617021 (-2775 3600);
PAINT SKYBLUE (-2775 3600);
FORCEPROP 1 LASTPIN (-2575 3700) $PN 2
J 0
(-2613 3712);
DISPLAY 0.617021 (-2613 3712);
PAINT ORANGE (-2613 3712);
FORCEPROP 1 LAST WATTAGE 1/16W
J 0
(-2775 3500);
DISPLAY 0.617021 (-2775 3500);
PAINT SKYBLUE (-2775 3500);
FORCEPROP 1 LAST PART_NUMBER G21497-005
J 0
(-2775 3400);
DISPLAY 0.617021 (-2775 3400);
PAINT BLUE (-2775 3400);
FORCEPROP 1 LAST TOLERANCE 5%
J 0
(-2775 3550);
DISPLAY 0.617021 (-2775 3550);
PAINT SKYBLUE (-2775 3550);
FORCEPROP 1 LAST PACK_TYPE 0402
J 0
(-2775 3450);
DISPLAY 0.617021 (-2775 3450);
PAINT SKYBLUE (-2775 3450);
FORCEPROP 1 LAST PATH I187
J 0
(-2725 3850);
DISPLAY 0.978723 (-2725 3850);
PAINT WHITE (-2725 3850);
DISPLAY INVISIBLE (-2725 3850);
FORCEPROP 2 LAST SEC_TYPE 0402
J 0
(-2725 3900);
DISPLAY 1.021277 (-2725 3900);
PAINT ORANGE (-2725 3900);
DISPLAY INVISIBLE (-2725 3900);
FORCEPROP 2 LAST CDS_LIB mstr_discrete
J 0
(-2675 3700);
PAINT ORANGE (-2675 3700);
DISPLAY INVISIBLE (-2675 3700);
FORCEPROP 2 LAST SEC 1
J 0
(-2725 3900);
DISPLAY 0.680851 (-2725 3900);
PAINT MONO (-2725 3900);
DISPLAY INVISIBLE (-2725 3900);
FORCEPROP 0 LAST ROOM IO_SLOT
J 0
(-2625 3800);
DISPLAY 1.021277 (-2625 3800);
PAINT ORANGE (-2625 3800);
DISPLAY INVISIBLE (-2625 3800);
FORCEPROP 0 LAST CDS_SEC 1
J 0
(-2400 3825);
DISPLAY INVISIBLE (-2400 3825);
FORCEPROP 2 LAST CDS_LOCATION R32W12
J 0
(-2550 3700);
DISPLAY 0.617021 (-2550 3700);
PAINT AQUA (-2550 3700);
DISPLAY INVISIBLE (-2550 3700);
FORCEADD CAP_A..1
(-2450 3200);
FORCEPROP 1 LAST LOCATION C32W1
J 0
(-2400 3300);
DISPLAY 0.617021 (-2400 3300);
PAINT AQUA (-2400 3300);
FORCEPROP 1 LAST VALUE 0.1UF
J 0
(-2400 3250);
DISPLAY 0.617021 (-2400 3250);
PAINT SKYBLUE (-2400 3250);
FORCEPROP 1 LAST VOLTAGE 16V
J 0
(-2400 3200);
DISPLAY 0.617021 (-2400 3200);
PAINT SKYBLUE (-2400 3200);
FORCEPROP 1 LASTPIN (-2450 3300) $PN 1
J 0
(-2440 3280);
DISPLAY 0.617021 (-2440 3280);
PAINT ORANGE (-2440 3280);
FORCEPROP 1 LAST PACK_TYPE 0402V
J 0
(-2400 3000);
DISPLAY 0.617021 (-2400 3000);
PAINT SKYBLUE (-2400 3000);
FORCEPROP 1 LAST MATERIAL X7R
J 0
(-2400 3100);
DISPLAY 0.617021 (-2400 3100);
PAINT SKYBLUE (-2400 3100);
FORCEPROP 1 LASTPIN (-2450 3100) $PN 2
J 0
(-2440 3080);
DISPLAY 0.617021 (-2440 3080);
PAINT ORANGE (-2440 3080);
FORCEPROP 1 LAST TOLERANCE 10%
J 0
(-2400 3150);
DISPLAY 0.617021 (-2400 3150);
PAINT SKYBLUE (-2400 3150);
FORCEPROP 1 LAST PART_NUMBER A36096-030
J 0
(-2400 3050);
DISPLAY 0.617021 (-2400 3050);
PAINT BLUE (-2400 3050);
FORCEPROP 1 LAST PATH I188
J 0
(-2400 3350);
DISPLAY 0.978723 (-2400 3350);
PAINT WHITE (-2400 3350);
DISPLAY INVISIBLE (-2400 3350);
FORCEPROP 0 LAST ROOM SMB_PE_HP_CPU1
J 0
(-2400 3400);
DISPLAY 1.021277 (-2400 3400);
PAINT ORANGE (-2400 3400);
DISPLAY INVISIBLE (-2400 3400);
FORCEPROP 2 LAST SEC_TYPE 0402V
J 0
(-2400 3400);
DISPLAY 1.021277 (-2400 3400);
PAINT ORANGE (-2400 3400);
DISPLAY INVISIBLE (-2400 3400);
FORCEPROP 2 LAST SEC 1
J 0
(-2400 3400);
DISPLAY 0.680851 (-2400 3400);
PAINT MONO (-2400 3400);
DISPLAY INVISIBLE (-2400 3400);
FORCEPROP 2 LAST CDS_LIB dev_discrete
J 0
(-2450 3200);
PAINT ORANGE (-2450 3200);
DISPLAY INVISIBLE (-2450 3200);
FORCEPROP 0 LAST CDS_SEC 1
J 0
(-2400 3350);
DISPLAY INVISIBLE (-2400 3350);
FORCEPROP 2 LAST CDS_LOCATION C32W1
J 0
(-2400 3300);
DISPLAY 0.617021 (-2400 3300);
PAINT AQUA (-2400 3300);
DISPLAY INVISIBLE (-2400 3300);
FORCEADD GND..1
(-2100 3500);
FORCEPROP 3 LASTPIN (-2100 3550) SIG_NAME GND\g
J 0
(-2090 3560);
DISPLAY 0.659574 (-2090 3560);
PAINT MONO (-2090 3560);
DISPLAY INVISIBLE (-2090 3560);
FORCEPROP 1 LAST PATH I189
J 0
(-2025 3500);
DISPLAY 0.872340 (-2025 3500);
PAINT AQUA (-2025 3500);
DISPLAY INVISIBLE (-2025 3500);
FORCEPROP 1 LAST HDL_POWER GND
J 0
(-2100 3650);
DISPLAY 0.872340 (-2100 3650);
PAINT GREEN (-2100 3650);
DISPLAY INVISIBLE (-2100 3650);
FORCEPROP 1 LAST BODY_TYPE PLUMBING
J 0
(-2145 3457);
DISPLAY 0.340426 (-2145 3457);
PAINT GREEN (-2145 3457);
DISPLAY INVISIBLE (-2145 3457);
FORCEPROP 1 LAST VOLTAGE 0
J 0
(-2100 3500);
PAINT SKYBLUE (-2100 3500);
DISPLAY INVISIBLE (-2100 3500);
FORCEPROP 2 LAST CDS_LIB mstr_symbols
J 0
(-2100 3500);
PAINT MONO (-2100 3500);
DISPLAY INVISIBLE (-2100 3500);
FORCEPROP 1 LAST SIZE 1B
J 0
(-2025 3450);
DISPLAY 0.872340 (-2025 3450);
PAINT GREEN (-2025 3450);
DISPLAY INVISIBLE (-2025 3450);
FORCEPROP 2 LAST BOM_COST NT_BASE_VRD
J 0
(-2400 3575);
DISPLAY 0.617021 (-2400 3575);
PAINT ORANGE (-2400 3575);
DISPLAY INVISIBLE (-2400 3575);
FORCEPROP 2 LAST ROOM P2V5_LAN_AUX_VR
J 0
(-2400 3575);
DISPLAY 0.617021 (-2400 3575);
PAINT ORANGE (-2400 3575);
DISPLAY INVISIBLE (-2400 3575);
FORCEADD CAP_A..1
(-2450 3975);
FORCEPROP 1 LAST PART_NUMBER A36096-030
J 0
(-2400 3825);
DISPLAY 0.617021 (-2400 3825);
PAINT BLUE (-2400 3825);
FORCEPROP 1 LAST PACK_TYPE 0402V
J 0
(-2400 3775);
DISPLAY 0.617021 (-2400 3775);
PAINT SKYBLUE (-2400 3775);
FORCEPROP 1 LAST MATERIAL X7R
J 0
(-2400 3875);
DISPLAY 0.617021 (-2400 3875);
PAINT SKYBLUE (-2400 3875);
FORCEPROP 1 LASTPIN (-2450 3875) $PN 2
J 0
(-2440 3855);
DISPLAY 0.617021 (-2440 3855);
PAINT ORANGE (-2440 3855);
FORCEPROP 1 LASTPIN (-2450 4075) $PN 1
J 0
(-2440 4055);
DISPLAY 0.617021 (-2440 4055);
PAINT ORANGE (-2440 4055);
FORCEPROP 1 LAST VOLTAGE 16V
J 0
(-2400 3975);
DISPLAY 0.617021 (-2400 3975);
PAINT SKYBLUE (-2400 3975);
FORCEPROP 1 LAST VALUE 0.1UF
J 0
(-2400 4025);
DISPLAY 0.617021 (-2400 4025);
PAINT SKYBLUE (-2400 4025);
FORCEPROP 1 LAST LOCATION C32W3
J 0
(-2400 4075);
DISPLAY 0.617021 (-2400 4075);
PAINT AQUA (-2400 4075);
FORCEPROP 1 LAST TOLERANCE 10%
J 0
(-2400 3925);
DISPLAY 0.617021 (-2400 3925);
PAINT SKYBLUE (-2400 3925);
FORCEPROP 1 LAST PATH I190
J 0
(-2400 4125);
DISPLAY 0.978723 (-2400 4125);
PAINT WHITE (-2400 4125);
DISPLAY INVISIBLE (-2400 4125);
FORCEPROP 0 LAST ROOM SMB_PE_HP_CPU1
J 0
(-2400 4175);
DISPLAY 1.021277 (-2400 4175);
PAINT ORANGE (-2400 4175);
DISPLAY INVISIBLE (-2400 4175);
FORCEPROP 2 LAST SEC_TYPE 0402V
J 0
(-2400 4175);
DISPLAY 1.021277 (-2400 4175);
PAINT ORANGE (-2400 4175);
DISPLAY INVISIBLE (-2400 4175);
FORCEPROP 2 LAST SEC 1
J 0
(-2400 4175);
DISPLAY 0.680851 (-2400 4175);
PAINT MONO (-2400 4175);
DISPLAY INVISIBLE (-2400 4175);
FORCEPROP 2 LAST CDS_LIB dev_discrete
J 0
(-2450 3975);
PAINT ORANGE (-2450 3975);
DISPLAY INVISIBLE (-2450 3975);
FORCEPROP 0 LAST CDS_SEC 1
J 0
(-2400 4125);
DISPLAY INVISIBLE (-2400 4125);
FORCEPROP 2 LAST CDS_LOCATION C32W3
J 0
(-2400 4075);
DISPLAY 0.617021 (-2400 4075);
PAINT AQUA (-2400 4075);
DISPLAY INVISIBLE (-2400 4075);
FORCEADD TCA9517DGKR-GP..1
(-1725 2900);
FORCEPROP 1 LAST VALUE TCA9517DGKR-GP
J 0
(-1895 2690);
DISPLAY 0.617021 (-1895 2690);
PAINT GREEN (-1895 2690);
FORCEPROP 2 LASTPIN (-1400 2925) $PN 7
J 0
(-1390 2935);
DISPLAY 0.808511 (-1390 2935);
PAINT ORANGE (-1390 2935);
FORCEPROP 2 LASTPIN (-1400 2875) $PN 6
J 0
(-1390 2885);
DISPLAY 0.808511 (-1390 2885);
PAINT ORANGE (-1390 2885);
FORCEPROP 2 LASTPIN (-1400 2825) $PN 5
J 0
(-1390 2835);
DISPLAY 0.808511 (-1390 2835);
PAINT ORANGE (-1390 2835);
FORCEPROP 2 LASTPIN (-2050 2825) $PN 4
J 2
(-2060 2835);
DISPLAY 0.808511 (-2060 2835);
PAINT ORANGE (-2060 2835);
FORCEPROP 2 LASTPIN (-2050 2975) $PN 1
J 2
(-2060 2985);
DISPLAY 0.808511 (-2060 2985);
PAINT ORANGE (-2060 2985);
FORCEPROP 2 LASTPIN (-1400 2975) $PN 8
J 0
(-1390 2985);
DISPLAY 0.808511 (-1390 2985);
PAINT ORANGE (-1390 2985);
FORCEPROP 2 LASTPIN (-2050 2925) $PN 2
J 2
(-2060 2935);
DISPLAY 0.808511 (-2060 2935);
PAINT ORANGE (-2060 2935);
FORCEPROP 2 LASTPIN (-2050 2875) $PN 3
J 2
(-2060 2885);
DISPLAY 0.808511 (-2060 2885);
PAINT ORANGE (-2060 2885);
FORCEPROP 1 LAST LOCATION U32W1
J 0
(-1895 3085);
DISPLAY 0.617021 (-1895 3085);
PAINT GREEN (-1895 3085);
FORCEPROP 1 LAST PATH I191
J 0
(-1725 2900);
DISPLAY 0.617021 (-1725 2900);
PAINT GREEN (-1725 2900);
DISPLAY INVISIBLE (-1725 2900);
FORCEPROP 0 LAST CDS_SEC 1
J 0
(-1875 3125);
DISPLAY INVISIBLE (-1875 3125);
FORCEPROP 1 LAST PACK_TYPE DISCRET-G8
J 0
(-1725 2900);
DISPLAY 0.617021 (-1725 2900);
PAINT GREEN (-1725 2900);
DISPLAY INVISIBLE (-1725 2900);
FORCEPROP 2 LAST SEC 1
J 0
(-1875 3125);
DISPLAY 0.680851 (-1875 3125);
PAINT MONO (-1875 3125);
DISPLAY INVISIBLE (-1875 3125);
FORCEPROP 2 LAST SEC_TYPE DISCRET-G8
J 0
(-1875 3125);
DISPLAY 1.021277 (-1875 3125);
PAINT ORANGE (-1875 3125);
DISPLAY INVISIBLE (-1875 3125);
FORCEPROP 1 LAST CDS_LMAN_SYM_OUTLINE -175,175,175,-175
J 0
(-1725 2900);
DISPLAY 0.468085 (-1725 2900);
PAINT GREEN (-1725 2900);
DISPLAY INVISIBLE (-1725 2900);
FORCEPROP 2 LAST CDS_LIB w_hdl
J 0
(-1725 2900);
PAINT MONO (-1725 2900);
DISPLAY INVISIBLE (-1725 2900);
FORCEPROP 1 LAST PART_NUMBER 071.09517.0009
J 0
(-1725 2900);
DISPLAY 0.617021 (-1725 2900);
PAINT GREEN (-1725 2900);
DISPLAY INVISIBLE (-1725 2900);
FORCEPROP 0 LAST CDS_LOCATION U32W1
J 0
(-1875 3125);
DISPLAY INVISIBLE (-1875 3125);
FORCEADD GND..1
(-1150 3000);
FORCEPROP 3 LASTPIN (-1150 3050) SIG_NAME GND\g
J 0
(-1140 3060);
DISPLAY 0.659574 (-1140 3060);
PAINT MONO (-1140 3060);
DISPLAY INVISIBLE (-1140 3060);
FORCEPROP 1 LAST PATH I192
J 0
(-1075 3000);
DISPLAY 0.872340 (-1075 3000);
PAINT AQUA (-1075 3000);
DISPLAY INVISIBLE (-1075 3000);
FORCEPROP 2 LAST ROOM P2V5_LAN_AUX_VR
J 0
(-1450 3075);
DISPLAY 0.617021 (-1450 3075);
PAINT ORANGE (-1450 3075);
DISPLAY INVISIBLE (-1450 3075);
FORCEPROP 2 LAST BOM_COST NT_BASE_VRD
J 0
(-1450 3075);
DISPLAY 0.617021 (-1450 3075);
PAINT ORANGE (-1450 3075);
DISPLAY INVISIBLE (-1450 3075);
FORCEPROP 1 LAST SIZE 1B
J 0
(-1075 2950);
DISPLAY 0.872340 (-1075 2950);
PAINT GREEN (-1075 2950);
DISPLAY INVISIBLE (-1075 2950);
FORCEPROP 2 LAST CDS_LIB mstr_symbols
J 0
(-1150 3000);
PAINT MONO (-1150 3000);
DISPLAY INVISIBLE (-1150 3000);
FORCEPROP 1 LAST VOLTAGE 0
J 0
(-1150 3000);
PAINT SKYBLUE (-1150 3000);
DISPLAY INVISIBLE (-1150 3000);
FORCEPROP 1 LAST BODY_TYPE PLUMBING
J 0
(-1195 2957);
DISPLAY 0.340426 (-1195 2957);
PAINT GREEN (-1195 2957);
DISPLAY INVISIBLE (-1195 2957);
FORCEPROP 1 LAST HDL_POWER GND
J 0
(-1150 3150);
DISPLAY 0.872340 (-1150 3150);
PAINT GREEN (-1150 3150);
DISPLAY INVISIBLE (-1150 3150);
FORCEADD CAP_A..1
(-1150 3200);
FORCEPROP 1 LAST PART_NUMBER A36096-030
J 0
(-1100 3050);
DISPLAY 0.617021 (-1100 3050);
PAINT BLUE (-1100 3050);
FORCEPROP 1 LAST VOLTAGE 16V
J 0
(-1100 3200);
DISPLAY 0.617021 (-1100 3200);
PAINT SKYBLUE (-1100 3200);
FORCEPROP 1 LASTPIN (-1150 3300) $PN 1
J 0
(-1140 3280);
DISPLAY 0.617021 (-1140 3280);
PAINT ORANGE (-1140 3280);
FORCEPROP 1 LASTPIN (-1150 3100) $PN 2
J 0
(-1140 3080);
DISPLAY 0.617021 (-1140 3080);
PAINT ORANGE (-1140 3080);
FORCEPROP 1 LAST MATERIAL X7R
J 0
(-1100 3100);
DISPLAY 0.617021 (-1100 3100);
PAINT SKYBLUE (-1100 3100);
FORCEPROP 1 LAST TOLERANCE 10%
J 0
(-1100 3150);
DISPLAY 0.617021 (-1100 3150);
PAINT SKYBLUE (-1100 3150);
FORCEPROP 1 LAST PACK_TYPE 0402V
J 0
(-1100 3000);
DISPLAY 0.617021 (-1100 3000);
PAINT SKYBLUE (-1100 3000);
FORCEPROP 1 LAST VALUE 0.1UF
J 0
(-1100 3250);
DISPLAY 0.617021 (-1100 3250);
PAINT SKYBLUE (-1100 3250);
FORCEPROP 1 LAST LOCATION C32W2
J 0
(-1100 3300);
DISPLAY 0.617021 (-1100 3300);
PAINT AQUA (-1100 3300);
FORCEPROP 1 LAST PATH I193
J 0
(-1100 3350);
DISPLAY 0.978723 (-1100 3350);
PAINT WHITE (-1100 3350);
DISPLAY INVISIBLE (-1100 3350);
FORCEPROP 0 LAST ROOM SMB_PE_HP_CPU1
J 0
(-1100 3400);
DISPLAY 1.021277 (-1100 3400);
PAINT ORANGE (-1100 3400);
DISPLAY INVISIBLE (-1100 3400);
FORCEPROP 2 LAST SEC_TYPE 0402V
J 0
(-1100 3400);
DISPLAY 1.021277 (-1100 3400);
PAINT ORANGE (-1100 3400);
DISPLAY INVISIBLE (-1100 3400);
FORCEPROP 2 LAST SEC 1
J 0
(-1100 3400);
DISPLAY 0.680851 (-1100 3400);
PAINT MONO (-1100 3400);
DISPLAY INVISIBLE (-1100 3400);
FORCEPROP 2 LAST CDS_LIB dev_discrete
J 0
(-1150 3200);
PAINT ORANGE (-1150 3200);
DISPLAY INVISIBLE (-1150 3200);
FORCEPROP 0 LAST CDS_SEC 1
J 0
(-1100 3350);
DISPLAY INVISIBLE (-1100 3350);
FORCEPROP 2 LAST CDS_LOCATION C32W2
J 0
(-1100 3300);
DISPLAY 0.617021 (-1100 3300);
PAINT AQUA (-1100 3300);
DISPLAY INVISIBLE (-1100 3300);
FORCEADD P3V3_STBY..1
(-1150 3450);
FORCEPROP 3 LASTPIN (-1150 3400) SIG_NAME P3V3_STBY\g
J 0
(-1140 3410);
DISPLAY 0.659574 (-1140 3410);
PAINT MONO (-1140 3410);
DISPLAY INVISIBLE (-1140 3410);
FORCEPROP 1 LAST PATH I194
J 0
(-1105 3452);
DISPLAY 0.340426 (-1105 3452);
PAINT GREEN (-1105 3452);
DISPLAY INVISIBLE (-1105 3452);
FORCEPROP 1 LAST VOLTAGE 3.3V
J 0
(-1195 3407);
DISPLAY 0.340426 (-1195 3407);
PAINT SKYBLUE (-1195 3407);
DISPLAY INVISIBLE (-1195 3407);
FORCEPROP 2 LAST CDS_LIB mstr_symbols
J 0
(-1150 3450);
PAINT ORANGE (-1150 3450);
DISPLAY INVISIBLE (-1150 3450);
FORCEPROP 1 LAST SIZE 1B
J 0
(-1105 3472);
DISPLAY 0.340426 (-1105 3472);
PAINT GREEN (-1105 3472);
DISPLAY INVISIBLE (-1105 3472);
FORCEPROP 1 LAST BODY_TYPE PLUMBING
J 0
(-1195 3407);
DISPLAY 0.340426 (-1195 3407);
PAINT GREEN (-1195 3407);
DISPLAY INVISIBLE (-1195 3407);
FORCEPROP 1 LAST HDL_POWER P3V3_STBY
J 0
(-1450 3325);
DISPLAY 0.872340 (-1450 3325);
PAINT ORANGE (-1450 3325);
DISPLAY INVISIBLE (-1450 3325);
FORCEADD GND..1
(-1200 3800);
FORCEPROP 3 LASTPIN (-1200 3850) SIG_NAME GND\g
J 0
(-1190 3860);
DISPLAY 0.659574 (-1190 3860);
PAINT MONO (-1190 3860);
DISPLAY INVISIBLE (-1190 3860);
FORCEPROP 1 LAST PATH I195
J 0
(-1125 3800);
DISPLAY 0.872340 (-1125 3800);
PAINT AQUA (-1125 3800);
DISPLAY INVISIBLE (-1125 3800);
FORCEPROP 2 LAST ROOM P2V5_LAN_AUX_VR
J 0
(-1500 3875);
DISPLAY 0.617021 (-1500 3875);
PAINT ORANGE (-1500 3875);
DISPLAY INVISIBLE (-1500 3875);
FORCEPROP 2 LAST BOM_COST NT_BASE_VRD
J 0
(-1500 3875);
DISPLAY 0.617021 (-1500 3875);
PAINT ORANGE (-1500 3875);
DISPLAY INVISIBLE (-1500 3875);
FORCEPROP 1 LAST SIZE 1B
J 0
(-1125 3750);
DISPLAY 0.872340 (-1125 3750);
PAINT GREEN (-1125 3750);
DISPLAY INVISIBLE (-1125 3750);
FORCEPROP 2 LAST CDS_LIB mstr_symbols
J 0
(-1200 3800);
PAINT MONO (-1200 3800);
DISPLAY INVISIBLE (-1200 3800);
FORCEPROP 1 LAST VOLTAGE 0
J 0
(-1200 3800);
PAINT SKYBLUE (-1200 3800);
DISPLAY INVISIBLE (-1200 3800);
FORCEPROP 1 LAST BODY_TYPE PLUMBING
J 0
(-1245 3757);
DISPLAY 0.340426 (-1245 3757);
PAINT GREEN (-1245 3757);
DISPLAY INVISIBLE (-1245 3757);
FORCEPROP 1 LAST HDL_POWER GND
J 0
(-1200 3950);
DISPLAY 0.872340 (-1200 3950);
PAINT GREEN (-1200 3950);
DISPLAY INVISIBLE (-1200 3950);
FORCEADD CAP_A..1
(-1200 4000);
FORCEPROP 1 LAST LOCATION C32W4
J 0
(-1150 4100);
DISPLAY 0.617021 (-1150 4100);
PAINT AQUA (-1150 4100);
FORCEPROP 1 LAST VALUE 0.1UF
J 0
(-1150 4050);
DISPLAY 0.617021 (-1150 4050);
PAINT SKYBLUE (-1150 4050);
FORCEPROP 1 LAST VOLTAGE 16V
J 0
(-1150 4000);
DISPLAY 0.617021 (-1150 4000);
PAINT SKYBLUE (-1150 4000);
FORCEPROP 1 LASTPIN (-1200 4100) $PN 1
J 0
(-1190 4080);
DISPLAY 0.617021 (-1190 4080);
PAINT ORANGE (-1190 4080);
FORCEPROP 1 LAST PACK_TYPE 0402V
J 0
(-1150 3800);
DISPLAY 0.617021 (-1150 3800);
PAINT SKYBLUE (-1150 3800);
FORCEPROP 1 LASTPIN (-1200 3900) $PN 2
J 0
(-1190 3880);
DISPLAY 0.617021 (-1190 3880);
PAINT ORANGE (-1190 3880);
FORCEPROP 1 LAST TOLERANCE 10%
J 0
(-1150 3950);
DISPLAY 0.617021 (-1150 3950);
PAINT SKYBLUE (-1150 3950);
FORCEPROP 1 LAST MATERIAL X7R
J 0
(-1150 3900);
DISPLAY 0.617021 (-1150 3900);
PAINT SKYBLUE (-1150 3900);
FORCEPROP 1 LAST PART_NUMBER A36096-030
J 0
(-1150 3850);
DISPLAY 0.617021 (-1150 3850);
PAINT BLUE (-1150 3850);
FORCEPROP 1 LAST PATH I196
J 0
(-1150 4150);
DISPLAY 0.978723 (-1150 4150);
PAINT WHITE (-1150 4150);
DISPLAY INVISIBLE (-1150 4150);
FORCEPROP 0 LAST CDS_SEC 1
J 0
(-1150 4150);
DISPLAY INVISIBLE (-1150 4150);
FORCEPROP 2 LAST CDS_LIB dev_discrete
J 0
(-1200 4000);
PAINT ORANGE (-1200 4000);
DISPLAY INVISIBLE (-1200 4000);
FORCEPROP 2 LAST SEC 1
J 0
(-1150 4200);
DISPLAY 0.680851 (-1150 4200);
PAINT MONO (-1150 4200);
DISPLAY INVISIBLE (-1150 4200);
FORCEPROP 2 LAST SEC_TYPE 0402V
J 0
(-1150 4200);
DISPLAY 1.021277 (-1150 4200);
PAINT ORANGE (-1150 4200);
DISPLAY INVISIBLE (-1150 4200);
FORCEPROP 0 LAST ROOM SMB_PE_HP_CPU1
J 0
(-1150 4200);
DISPLAY 1.021277 (-1150 4200);
PAINT ORANGE (-1150 4200);
DISPLAY INVISIBLE (-1150 4200);
FORCEPROP 2 LAST CDS_LOCATION C32W4
J 0
(-1150 4100);
DISPLAY 0.617021 (-1150 4100);
PAINT AQUA (-1150 4100);
DISPLAY INVISIBLE (-1150 4100);
FORCEADD OFFPAGE..3
(-625 2875);
FORCEPROP 2 LAST $XR1 186 
J 0
(-291 2875);
DISPLAY 0.638298 (-291 2875);
PAINT MONO (-291 2875);
FORCEPROP 2 LAST $XR0 159 
J 0
(-411 2875);
DISPLAY 0.638298 (-411 2875);
PAINT MONO (-411 2875);
FORCEPROP 2 LAST PATH I197
J 0
(-275 2925);
DISPLAY 1.021277 (-275 2925);
PAINT ORANGE (-275 2925);
DISPLAY INVISIBLE (-275 2925);
FORCEPROP 1 LAST COMMENT_BODY TRUE
J 0
(-675 2775);
DISPLAY 0.872340 (-675 2775);
PAINT GREEN (-675 2775);
DISPLAY INVISIBLE (-675 2775);
FORCEPROP 1 LAST OFFPAGE TRUE
J 0
(-300 2750);
DISPLAY 0.872340 (-300 2750);
PAINT GREEN (-300 2750);
DISPLAY INVISIBLE (-300 2750);
FORCEPROP 2 LAST CDS_LIB mstr_standard
J 2
(-625 2875);
PAINT MONO (-625 2875);
DISPLAY INVISIBLE (-625 2875);
FORCEADD OFFPAGE..4
(-625 2925);
FORCEPROP 2 LAST $XR1 186 
J 0
(-319 2925);
DISPLAY 0.638298 (-319 2925);
PAINT MONO (-319 2925);
FORCEPROP 2 LAST $XR0 159 
J 0
(-439 2925);
DISPLAY 0.638298 (-439 2925);
PAINT MONO (-439 2925);
FORCEPROP 2 LAST PATH I198
J 0
(-300 2975);
DISPLAY 1.021277 (-300 2975);
PAINT ORANGE (-300 2975);
DISPLAY INVISIBLE (-300 2975);
FORCEPROP 1 LAST OFFPAGE TRUE
J 0
(-300 2800);
DISPLAY 0.872340 (-300 2800);
PAINT GREEN (-300 2800);
DISPLAY INVISIBLE (-300 2800);
FORCEPROP 2 LAST CDS_LIB mstr_standard
J 0
(-625 2925);
PAINT ORANGE (-625 2925);
DISPLAY INVISIBLE (-625 2925);
FORCEPROP 1 LAST COMMENT_BODY TRUE
J 0
(-650 2825);
DISPLAY 0.872340 (-650 2825);
PAINT GREEN (-650 2825);
DISPLAY INVISIBLE (-650 2825);
FORCEADD GND..1
(-850 3250);
FORCEPROP 3 LASTPIN (-850 3300) SIG_NAME GND\g
J 0
(-840 3310);
DISPLAY 0.659574 (-840 3310);
PAINT MONO (-840 3310);
DISPLAY INVISIBLE (-840 3310);
FORCEPROP 1 LAST PATH I199
J 0
(-775 3250);
DISPLAY 0.872340 (-775 3250);
PAINT AQUA (-775 3250);
DISPLAY INVISIBLE (-775 3250);
FORCEPROP 2 LAST ROOM P2V5_LAN_AUX_VR
J 0
(-1150 3325);
DISPLAY 0.617021 (-1150 3325);
PAINT ORANGE (-1150 3325);
DISPLAY INVISIBLE (-1150 3325);
FORCEPROP 2 LAST BOM_COST NT_BASE_VRD
J 0
(-1150 3325);
DISPLAY 0.617021 (-1150 3325);
PAINT ORANGE (-1150 3325);
DISPLAY INVISIBLE (-1150 3325);
FORCEPROP 1 LAST SIZE 1B
J 0
(-775 3200);
DISPLAY 0.872340 (-775 3200);
PAINT GREEN (-775 3200);
DISPLAY INVISIBLE (-775 3200);
FORCEPROP 2 LAST CDS_LIB mstr_symbols
J 0
(-850 3250);
PAINT MONO (-850 3250);
DISPLAY INVISIBLE (-850 3250);
FORCEPROP 1 LAST VOLTAGE 0
J 0
(-850 3250);
PAINT SKYBLUE (-850 3250);
DISPLAY INVISIBLE (-850 3250);
FORCEPROP 1 LAST BODY_TYPE PLUMBING
J 0
(-895 3207);
DISPLAY 0.340426 (-895 3207);
PAINT GREEN (-895 3207);
DISPLAY INVISIBLE (-895 3207);
FORCEPROP 1 LAST HDL_POWER GND
J 0
(-850 3400);
DISPLAY 0.872340 (-850 3400);
PAINT GREEN (-850 3400);
DISPLAY INVISIBLE (-850 3400);
FORCEADD RES..2
(-850 3450);
FORCEPROP 1 LASTPIN (-850 3350) $PN 2
J 0
(-845 3360);
DISPLAY 0.617021 (-845 3360);
PAINT ORANGE (-845 3360);
FORCEPROP 1 LAST WATTAGE 1/16W
J 0
(-760 3425);
DISPLAY 0.617021 (-760 3425);
PAINT SKYBLUE (-760 3425);
FORCEPROP 1 LAST TOLERANCE 1%
J 0
(-755 3475);
DISPLAY 0.617021 (-755 3475);
PAINT SKYBLUE (-755 3475);
FORCEPROP 1 LAST LOCATION R32W9
J 0
(-755 3575);
DISPLAY 0.617021 (-755 3575);
PAINT AQUA (-755 3575);
FORCEPROP 1 LAST VALUE 10.0K
J 0
(-755 3525);
DISPLAY 0.617021 (-755 3525);
PAINT SKYBLUE (-755 3525);
FORCEPROP 1 LASTPIN (-850 3550) $PN 1
J 0
(-845 3512);
DISPLAY 0.617021 (-845 3512);
PAINT ORANGE (-845 3512);
FORCEPROP 1 LAST PART_NUMBER G21796-016
R 1
J 0
(-785 3325);
DISPLAY 0.617021 (-785 3325);
PAINT BLUE (-785 3325);
FORCEPROP 1 LAST MATERIAL CHIP
J 0
(-760 3375);
DISPLAY 0.617021 (-760 3375);
PAINT SKYBLUE (-760 3375);
FORCEPROP 1 LAST PACK_TYPE 0402
J 0
(-760 3325);
DISPLAY 0.617021 (-760 3325);
PAINT SKYBLUE (-760 3325);
FORCEPROP 0 LAST POP NOPOP
J 0
(-750 3275);
DISPLAY 0.638298 (-750 3275);
PAINT RED (-750 3275);
FORCEPROP 1 LAST PATH I200
J 0
(-800 3625);
DISPLAY 0.978723 (-800 3625);
PAINT WHITE (-800 3625);
DISPLAY INVISIBLE (-800 3625);
FORCEPROP 0 LAST CDS_SEC 1
J 0
(-750 3625);
DISPLAY INVISIBLE (-750 3625);
FORCEPROP 2 LAST SEC_TYPE 0402
J 0
(-800 3675);
DISPLAY 1.021277 (-800 3675);
PAINT ORANGE (-800 3675);
DISPLAY INVISIBLE (-800 3675);
FORCEPROP 2 LAST SEC 1
J 0
(-800 3675);
DISPLAY 0.680851 (-800 3675);
PAINT MONO (-800 3675);
DISPLAY INVISIBLE (-800 3675);
FORCEPROP 2 LAST BOM_COST PROC_SIDEBAND
J 0
(-850 3450);
PAINT WHITE (-850 3450);
DISPLAY INVISIBLE (-850 3450);
FORCEPROP 2 LAST CDS_LIB mstr_discrete
J 2
(-850 3450);
PAINT ORANGE (-850 3450);
DISPLAY INVISIBLE (-850 3450);
FORCEPROP 2 LAST ROOM CPU0
J 0
(-825 3225);
PAINT WHITE (-825 3225);
DISPLAY INVISIBLE (-825 3225);
FORCEPROP 2 LAST CDS_LOCATION R32W9
J 0
(-805 3575);
DISPLAY 0.617021 (-805 3575);
PAINT AQUA (-805 3575);
DISPLAY INVISIBLE (-805 3575);
FORCEADD OFFPAGE..2
(-700 3700);
FORCEPROP 2 LAST $XR3 145 
J 0
(-511 3664);
DISPLAY 0.638298 (-511 3664);
PAINT MONO (-511 3664);
FORCEPROP 2 LAST $XR2 119 
J 0
(-271 3700);
DISPLAY 0.638298 (-271 3700);
PAINT MONO (-271 3700);
FORCEPROP 2 LAST $XR1 186 
J 0
(-391 3700);
DISPLAY 0.638298 (-391 3700);
PAINT MONO (-391 3700);
FORCEPROP 2 LAST $XR0 157 
J 0
(-511 3700);
DISPLAY 0.638298 (-511 3700);
PAINT MONO (-511 3700);
FORCEPROP 2 LAST PATH I201
J 0
(-250 3750);
DISPLAY 1.021277 (-250 3750);
PAINT ORANGE (-250 3750);
DISPLAY INVISIBLE (-250 3750);
FORCEPROP 2 LAST CDS_LIB mstr_standard
J 2
(-700 3700);
PAINT MONO (-700 3700);
DISPLAY INVISIBLE (-700 3700);
FORCEPROP 1 LAST OFFPAGE TRUE
J 0
(-375 3575);
DISPLAY 0.872340 (-375 3575);
PAINT GREEN (-375 3575);
DISPLAY INVISIBLE (-375 3575);
FORCEPROP 1 LAST COMMENT_BODY TRUE
J 0
(-745 3605);
DISPLAY 0.872340 (-745 3605);
PAINT GREEN (-745 3605);
DISPLAY INVISIBLE (-745 3605);
FORCEADD P3V3_STBY..1
(-1300 4225);
FORCEPROP 3 LASTPIN (-1300 4175) SIG_NAME P3V3_STBY\g
J 0
(-1290 4185);
DISPLAY 0.659574 (-1290 4185);
PAINT MONO (-1290 4185);
DISPLAY INVISIBLE (-1290 4185);
FORCEPROP 1 LAST PATH I202
J 0
(-1255 4227);
DISPLAY 0.340426 (-1255 4227);
PAINT GREEN (-1255 4227);
DISPLAY INVISIBLE (-1255 4227);
FORCEPROP 1 LAST VOLTAGE 3.3V
J 0
(-1345 4182);
DISPLAY 0.340426 (-1345 4182);
PAINT SKYBLUE (-1345 4182);
DISPLAY INVISIBLE (-1345 4182);
FORCEPROP 2 LAST CDS_LIB mstr_symbols
J 0
(-1300 4225);
PAINT ORANGE (-1300 4225);
DISPLAY INVISIBLE (-1300 4225);
FORCEPROP 1 LAST SIZE 1B
J 0
(-1255 4247);
DISPLAY 0.340426 (-1255 4247);
PAINT GREEN (-1255 4247);
DISPLAY INVISIBLE (-1255 4247);
FORCEPROP 1 LAST BODY_TYPE PLUMBING
J 0
(-1345 4182);
DISPLAY 0.340426 (-1345 4182);
PAINT GREEN (-1345 4182);
DISPLAY INVISIBLE (-1345 4182);
FORCEPROP 1 LAST HDL_POWER P3V3_STBY
J 0
(-1600 4100);
DISPLAY 0.872340 (-1600 4100);
PAINT ORANGE (-1600 4100);
DISPLAY INVISIBLE (-1600 4100);
FORCEADD GND..1
(-2450 3775);
FORCEPROP 3 LASTPIN (-2450 3825) SIG_NAME GND\g
J 0
(-2440 3835);
DISPLAY 0.659574 (-2440 3835);
PAINT MONO (-2440 3835);
DISPLAY INVISIBLE (-2440 3835);
FORCEPROP 1 LAST PATH I203
J 0
(-2375 3775);
DISPLAY 0.872340 (-2375 3775);
PAINT AQUA (-2375 3775);
DISPLAY INVISIBLE (-2375 3775);
FORCEPROP 2 LAST ROOM P2V5_LAN_AUX_VR
J 0
(-2750 3850);
DISPLAY 0.617021 (-2750 3850);
PAINT ORANGE (-2750 3850);
DISPLAY INVISIBLE (-2750 3850);
FORCEPROP 2 LAST BOM_COST NT_BASE_VRD
J 0
(-2750 3850);
DISPLAY 0.617021 (-2750 3850);
PAINT ORANGE (-2750 3850);
DISPLAY INVISIBLE (-2750 3850);
FORCEPROP 1 LAST SIZE 1B
J 0
(-2375 3725);
DISPLAY 0.872340 (-2375 3725);
PAINT GREEN (-2375 3725);
DISPLAY INVISIBLE (-2375 3725);
FORCEPROP 2 LAST CDS_LIB mstr_symbols
J 0
(-2450 3775);
PAINT MONO (-2450 3775);
DISPLAY INVISIBLE (-2450 3775);
FORCEPROP 1 LAST VOLTAGE 0
J 0
(-2450 3775);
PAINT SKYBLUE (-2450 3775);
DISPLAY INVISIBLE (-2450 3775);
FORCEPROP 1 LAST BODY_TYPE PLUMBING
J 0
(-2495 3732);
DISPLAY 0.340426 (-2495 3732);
PAINT GREEN (-2495 3732);
DISPLAY INVISIBLE (-2495 3732);
FORCEPROP 1 LAST HDL_POWER GND
J 0
(-2450 3925);
DISPLAY 0.872340 (-2450 3925);
PAINT GREEN (-2450 3925);
DISPLAY INVISIBLE (-2450 3925);
FORCEADD TCA9517DGKR-GP..1
(-1725 3675);
FORCEPROP 2 LASTPIN (-2050 3650) $PN 3
J 2
(-2060 3660);
DISPLAY 0.808511 (-2060 3660);
PAINT ORANGE (-2060 3660);
FORCEPROP 1 LAST LOCATION U32W2
J 0
(-1895 3860);
DISPLAY 0.617021 (-1895 3860);
PAINT GREEN (-1895 3860);
FORCEPROP 2 LASTPIN (-2050 3750) $PN 1
J 2
(-2060 3760);
DISPLAY 0.808511 (-2060 3760);
PAINT ORANGE (-2060 3760);
FORCEPROP 2 LASTPIN (-1400 3750) $PN 8
J 0
(-1390 3760);
DISPLAY 0.808511 (-1390 3760);
PAINT ORANGE (-1390 3760);
FORCEPROP 2 LASTPIN (-1400 3600) $PN 5
J 0
(-1390 3610);
DISPLAY 0.808511 (-1390 3610);
PAINT ORANGE (-1390 3610);
FORCEPROP 2 LASTPIN (-1400 3700) $PN 7
J 0
(-1390 3710);
DISPLAY 0.808511 (-1390 3710);
PAINT ORANGE (-1390 3710);
FORCEPROP 2 LASTPIN (-1400 3650) $PN 6
J 0
(-1390 3660);
DISPLAY 0.808511 (-1390 3660);
PAINT ORANGE (-1390 3660);
FORCEPROP 2 LASTPIN (-2050 3600) $PN 4
J 2
(-2060 3610);
DISPLAY 0.808511 (-2060 3610);
PAINT ORANGE (-2060 3610);
FORCEPROP 2 LASTPIN (-2050 3700) $PN 2
J 2
(-2060 3710);
DISPLAY 0.808511 (-2060 3710);
PAINT ORANGE (-2060 3710);
FORCEPROP 1 LAST VALUE TCA9517DGKR-GP
J 0
(-1895 3465);
DISPLAY 0.617021 (-1895 3465);
PAINT GREEN (-1895 3465);
FORCEPROP 1 LAST PATH I204
J 0
(-1725 3675);
DISPLAY 0.617021 (-1725 3675);
PAINT GREEN (-1725 3675);
DISPLAY INVISIBLE (-1725 3675);
FORCEPROP 1 LAST PART_NUMBER 071.09517.0009
J 0
(-1725 3675);
DISPLAY 0.617021 (-1725 3675);
PAINT GREEN (-1725 3675);
DISPLAY INVISIBLE (-1725 3675);
FORCEPROP 2 LAST CDS_LIB w_hdl
J 0
(-1725 3675);
PAINT MONO (-1725 3675);
DISPLAY INVISIBLE (-1725 3675);
FORCEPROP 1 LAST CDS_LMAN_SYM_OUTLINE -175,175,175,-175
J 0
(-1725 3675);
DISPLAY 0.468085 (-1725 3675);
PAINT GREEN (-1725 3675);
DISPLAY INVISIBLE (-1725 3675);
FORCEPROP 2 LAST SEC_TYPE DISCRET-G8
J 0
(-1875 3900);
DISPLAY 1.021277 (-1875 3900);
PAINT ORANGE (-1875 3900);
DISPLAY INVISIBLE (-1875 3900);
FORCEPROP 2 LAST SEC 1
J 0
(-1875 3900);
DISPLAY 0.680851 (-1875 3900);
PAINT MONO (-1875 3900);
DISPLAY INVISIBLE (-1875 3900);
FORCEPROP 1 LAST PACK_TYPE DISCRET-G8
J 0
(-1725 3675);
DISPLAY 0.617021 (-1725 3675);
PAINT GREEN (-1725 3675);
DISPLAY INVISIBLE (-1725 3675);
FORCEPROP 0 LAST CDS_SEC 1
J 0
(-1875 3900);
DISPLAY INVISIBLE (-1875 3900);
FORCEPROP 0 LAST CDS_LOCATION U32W2
J 0
(-1875 3900);
DISPLAY INVISIBLE (-1875 3900);
FORCEADD GND..1
(-7800 1175);
FORCEPROP 3 LASTPIN (-7800 1225) SIG_NAME GND\g
J 0
(-7790 1235);
DISPLAY 0.659574 (-7790 1235);
PAINT MONO (-7790 1235);
DISPLAY INVISIBLE (-7790 1235);
FORCEPROP 1 LAST PATH I205
J 0
(-7725 1175);
DISPLAY 0.872340 (-7725 1175);
PAINT AQUA (-7725 1175);
DISPLAY INVISIBLE (-7725 1175);
FORCEPROP 1 LAST BODY_TYPE PLUMBING
J 0
(-7845 1132);
DISPLAY 0.340426 (-7845 1132);
PAINT GREEN (-7845 1132);
DISPLAY INVISIBLE (-7845 1132);
FORCEPROP 1 LAST SIZE 1B
J 0
(-7725 1125);
DISPLAY 0.872340 (-7725 1125);
PAINT AQUA (-7725 1125);
DISPLAY INVISIBLE (-7725 1125);
FORCEPROP 1 LAST VOLTAGE 0.0V
J 0
(-7845 1132);
DISPLAY 0.340426 (-7845 1132);
PAINT SKYBLUE (-7845 1132);
DISPLAY INVISIBLE (-7845 1132);
FORCEPROP 2 LAST CDS_LIB mstr_symbols
J 0
(-7800 1175);
PAINT ORANGE (-7800 1175);
DISPLAY INVISIBLE (-7800 1175);
FORCEPROP 1 LAST HDL_POWER GND
J 0
(-7800 1325);
DISPLAY 0.872340 (-7800 1325);
PAINT GREEN (-7800 1325);
DISPLAY INVISIBLE (-7800 1325);
FORCEADD RES..1
R 5
(-7800 1350);
FORCEPROP 1 LASTPIN (-7800 1250) $PN 2
J 0
(-7788 1238);
DISPLAY 0.787234 (-7788 1238);
PAINT ORANGE (-7788 1238);
FORCEPROP 1 LAST WATTAGE 1/16W
J 0
(-7750 1275);
DISPLAY 0.638298 (-7750 1275);
PAINT SKYBLUE (-7750 1275);
FORCEPROP 1 LAST PACK_TYPE 0402
J 0
(-7600 1325);
DISPLAY 0.638298 (-7600 1325);
PAINT SKYBLUE (-7600 1325);
FORCEPROP 1 LAST VALUE 3.3K
J 0
(-7750 1375);
DISPLAY 0.638298 (-7750 1375);
PAINT SKYBLUE (-7750 1375);
FORCEPROP 1 LAST LOCATION R32W3
J 0
(-7750 1425);
DISPLAY 0.638298 (-7750 1425);
PAINT SKYBLUE (-7750 1425);
FORCEPROP 1 LASTPIN (-7800 1450) $PN 1
J 0
(-7788 1438);
DISPLAY 0.787234 (-7788 1438);
PAINT ORANGE (-7788 1438);
FORCEPROP 1 LAST TOLERANCE 5%
J 0
(-7750 1325);
DISPLAY 0.638298 (-7750 1325);
PAINT SKYBLUE (-7750 1325);
FORCEPROP 1 LAST PART_NUMBER G21497-013
J 0
(-7600 1375);
DISPLAY 0.638298 (-7600 1375);
PAINT BLUE (-7600 1375);
FORCEPROP 1 LAST MATERIAL CHIP
J 0
(-7600 1425);
DISPLAY 0.638298 (-7600 1425);
PAINT SKYBLUE (-7600 1425);
FORCEPROP 1 LAST PATH I206
R 3
J 0
(-7650 1400);
DISPLAY 0.978723 (-7650 1400);
PAINT WHITE (-7650 1400);
DISPLAY INVISIBLE (-7650 1400);
FORCEPROP 0 LAST CDS_SEC 1
J 0
(-7600 1475);
DISPLAY INVISIBLE (-7600 1475);
FORCEPROP 0 LAST CDS_LOCATION R32W3
J 0
(-7600 1475);
DISPLAY INVISIBLE (-7600 1475);
FORCEPROP 2 LAST SEC 1
J 0
(-7775 1475);
DISPLAY 0.680851 (-7775 1475);
PAINT MONO (-7775 1475);
DISPLAY INVISIBLE (-7775 1475);
FORCEPROP 2 LAST SEC_TYPE 0402
J 0
(-7775 1475);
DISPLAY 1.021277 (-7775 1475);
PAINT ORANGE (-7775 1475);
DISPLAY INVISIBLE (-7775 1475);
FORCEPROP 2 LAST CDS_LIB mstr_discrete
R 3
J 0
(-7800 1350);
PAINT MONO (-7800 1350);
DISPLAY INVISIBLE (-7800 1350);
FORCEADD RES..2
(-7800 1650);
FORCEPROP 1 LAST PART_NUMBER G21796-003
J 0
(-7610 1675);
DISPLAY 0.617021 (-7610 1675);
PAINT BLUE (-7610 1675);
FORCEPROP 1 LAST VALUE 1.5K
J 0
(-7755 1675);
DISPLAY 0.617021 (-7755 1675);
PAINT SKYBLUE (-7755 1675);
FORCEPROP 1 LAST PACK_TYPE 0402
J 0
(-7610 1625);
DISPLAY 0.617021 (-7610 1625);
PAINT SKYBLUE (-7610 1625);
FORCEPROP 1 LASTPIN (-7800 1750) $PN 1
J 0
(-7795 1712);
DISPLAY 0.617021 (-7795 1712);
PAINT ORANGE (-7795 1712);
FORCEPROP 1 LAST MATERIAL CHIP
J 0
(-7610 1725);
DISPLAY 0.617021 (-7610 1725);
PAINT SKYBLUE (-7610 1725);
FORCEPROP 1 LAST WATTAGE 1/16W
J 0
(-7760 1575);
DISPLAY 0.617021 (-7760 1575);
PAINT SKYBLUE (-7760 1575);
FORCEPROP 1 LAST TOLERANCE 1%
J 0
(-7755 1625);
DISPLAY 0.617021 (-7755 1625);
PAINT SKYBLUE (-7755 1625);
FORCEPROP 1 LASTPIN (-7800 1550) $PN 2
J 0
(-7795 1560);
DISPLAY 0.617021 (-7795 1560);
PAINT ORANGE (-7795 1560);
FORCEPROP 1 LAST LOCATION R32W2
J 0
(-7755 1725);
DISPLAY 0.617021 (-7755 1725);
PAINT AQUA (-7755 1725);
FORCEPROP 1 LAST PATH I207
J 0
(-7750 1825);
DISPLAY 0.978723 (-7750 1825);
PAINT WHITE (-7750 1825);
DISPLAY INVISIBLE (-7750 1825);
FORCEPROP 0 LAST CDS_SEC 1
J 0
(-7600 1775);
DISPLAY INVISIBLE (-7600 1775);
FORCEPROP 2 LAST CDS_LOCATION R32W2
J 0
(-7755 1775);
DISPLAY 0.617021 (-7755 1775);
PAINT AQUA (-7755 1775);
DISPLAY INVISIBLE (-7755 1775);
FORCEPROP 2 LAST ROOM PVCCIN_CPU0_VR
J 0
(-7750 1825);
DISPLAY 1.361702 (-7750 1825);
PAINT ORANGE (-7750 1825);
DISPLAY INVISIBLE (-7750 1825);
FORCEPROP 2 LAST SEC 1
J 0
(-7750 1875);
DISPLAY 0.680851 (-7750 1875);
PAINT MONO (-7750 1875);
DISPLAY INVISIBLE (-7750 1875);
FORCEPROP 2 LAST SEC_TYPE 0402
J 0
(-7750 1875);
DISPLAY 1.021277 (-7750 1875);
PAINT ORANGE (-7750 1875);
DISPLAY INVISIBLE (-7750 1875);
FORCEPROP 2 LAST CDS_LIB mstr_discrete
J 0
(-7800 1650);
PAINT ORANGE (-7800 1650);
DISPLAY INVISIBLE (-7800 1650);
FORCEADD RES..2
(-7800 1950);
FORCEPROP 1 LAST WATTAGE 1/16W
J 0
(-7760 1875);
DISPLAY 0.617021 (-7760 1875);
PAINT SKYBLUE (-7760 1875);
FORCEPROP 1 LASTPIN (-7800 1850) $PN 2
J 0
(-7795 1860);
DISPLAY 0.617021 (-7795 1860);
PAINT ORANGE (-7795 1860);
FORCEPROP 1 LAST TOLERANCE 1%
J 0
(-7755 1925);
DISPLAY 0.617021 (-7755 1925);
PAINT SKYBLUE (-7755 1925);
FORCEPROP 1 LAST MATERIAL CHIP
J 0
(-7610 2025);
DISPLAY 0.617021 (-7610 2025);
PAINT SKYBLUE (-7610 2025);
FORCEPROP 1 LAST PACK_TYPE 0402
J 0
(-7610 1925);
DISPLAY 0.617021 (-7610 1925);
PAINT SKYBLUE (-7610 1925);
FORCEPROP 1 LAST PART_NUMBER G21796-082
J 0
(-7610 1975);
DISPLAY 0.617021 (-7610 1975);
PAINT BLUE (-7610 1975);
FORCEPROP 1 LAST VALUE 4.02K
J 0
(-7755 1975);
DISPLAY 0.617021 (-7755 1975);
PAINT SKYBLUE (-7755 1975);
FORCEPROP 1 LAST LOCATION R32W1
J 0
(-7755 2025);
DISPLAY 0.617021 (-7755 2025);
PAINT AQUA (-7755 2025);
FORCEPROP 1 LASTPIN (-7800 2050) $PN 1
J 0
(-7795 2012);
DISPLAY 0.617021 (-7795 2012);
PAINT ORANGE (-7795 2012);
FORCEPROP 1 LAST PATH I208
J 0
(-7750 2125);
DISPLAY 0.978723 (-7750 2125);
PAINT WHITE (-7750 2125);
DISPLAY INVISIBLE (-7750 2125);
FORCEPROP 0 LAST CDS_SEC 1
J 0
(-7600 2075);
DISPLAY INVISIBLE (-7600 2075);
FORCEPROP 0 LAST CDS_LOCATION R32W1
J 0
(-7600 2075);
DISPLAY INVISIBLE (-7600 2075);
FORCEPROP 2 LAST SEC_TYPE 0402
J 0
(-7750 2175);
DISPLAY 1.021277 (-7750 2175);
PAINT ORANGE (-7750 2175);
DISPLAY INVISIBLE (-7750 2175);
FORCEPROP 2 LAST CDS_LIB mstr_discrete
J 0
(-7800 1950);
PAINT ORANGE (-7800 1950);
DISPLAY INVISIBLE (-7800 1950);
FORCEPROP 2 LAST SEC 1
J 0
(-7750 2175);
PAINT MONO (-7750 2175);
DISPLAY INVISIBLE (-7750 2175);
FORCEPROP 0 LAST ROOM PVCCIN_CPU1_VR
J 0
(-7750 2175);
DISPLAY 1.021277 (-7750 2175);
PAINT ORANGE (-7750 2175);
DISPLAY INVISIBLE (-7750 2175);
FORCEADD P3V3..1
(-7800 2150);
FORCEPROP 3 LASTPIN (-7800 2100) SIG_NAME P3V3\g
J 0
(-7790 2110);
DISPLAY 0.659574 (-7790 2110);
PAINT MONO (-7790 2110);
DISPLAY INVISIBLE (-7790 2110);
FORCEPROP 1 LAST PATH I209
J 0
(-7755 2152);
DISPLAY 0.340426 (-7755 2152);
PAINT GREEN (-7755 2152);
DISPLAY INVISIBLE (-7755 2152);
FORCEPROP 1 LAST VOLTAGE 3.3V
J 0
(-7845 2107);
DISPLAY 0.340426 (-7845 2107);
PAINT SKYBLUE (-7845 2107);
DISPLAY INVISIBLE (-7845 2107);
FORCEPROP 1 LAST SIZE 1B
J 0
(-7755 2172);
DISPLAY 0.340426 (-7755 2172);
PAINT GREEN (-7755 2172);
DISPLAY INVISIBLE (-7755 2172);
FORCEPROP 2 LAST CDS_LIB mstr_symbols
J 0
(-7800 2150);
PAINT ORANGE (-7800 2150);
DISPLAY INVISIBLE (-7800 2150);
FORCEPROP 1 LAST BODY_TYPE PLUMBING
J 0
(-7845 2107);
DISPLAY 0.340426 (-7845 2107);
PAINT GREEN (-7845 2107);
DISPLAY INVISIBLE (-7845 2107);
FORCEPROP 1 LAST HDL_POWER P3V3
J 0
(-8125 2025);
DISPLAY 0.872340 (-8125 2025);
PAINT ORANGE (-8125 2025);
DISPLAY INVISIBLE (-8125 2025);
FORCEADD GND..1
(-7900 700);
FORCEPROP 3 LASTPIN (-7900 750) SIG_NAME GND\g
J 0
(-7890 760);
DISPLAY 0.659574 (-7890 760);
PAINT MONO (-7890 760);
DISPLAY INVISIBLE (-7890 760);
FORCEPROP 1 LAST HDL_POWER GND
J 0
(-7900 850);
DISPLAY 0.872340 (-7900 850);
PAINT GREEN (-7900 850);
DISPLAY INVISIBLE (-7900 850);
FORCEPROP 2 LAST CDS_LIB mstr_symbols
J 0
(-7900 700);
PAINT ORANGE (-7900 700);
DISPLAY INVISIBLE (-7900 700);
FORCEPROP 1 LAST VOLTAGE 0.0V
J 0
(-7945 657);
DISPLAY 0.340426 (-7945 657);
PAINT SKYBLUE (-7945 657);
DISPLAY INVISIBLE (-7945 657);
FORCEPROP 1 LAST SIZE 1B
J 0
(-7825 650);
DISPLAY 0.872340 (-7825 650);
PAINT AQUA (-7825 650);
DISPLAY INVISIBLE (-7825 650);
FORCEPROP 1 LAST BODY_TYPE PLUMBING
J 0
(-7945 657);
DISPLAY 0.340426 (-7945 657);
PAINT GREEN (-7945 657);
DISPLAY INVISIBLE (-7945 657);
FORCEPROP 1 LAST PATH I210
J 0
(-7825 700);
DISPLAY 0.872340 (-7825 700);
PAINT AQUA (-7825 700);
DISPLAY INVISIBLE (-7825 700);
FORCEADD RES..2
(-7900 900);
FORCEPROP 1 LASTPIN (-7900 800) $PN 2
J 0
(-7895 810);
DISPLAY 0.787234 (-7895 810);
PAINT ORANGE (-7895 810);
FORCEPROP 1 LASTPIN (-7900 1000) $PN 1
J 0
(-7895 962);
DISPLAY 0.787234 (-7895 962);
PAINT ORANGE (-7895 962);
FORCEPROP 0 LAST POP NOPOP
J 0
(-7850 750);
DISPLAY 0.638298 (-7850 750);
PAINT RED (-7850 750);
FORCEPROP 1 LAST LOCATION R32W4
J 0
(-7855 950);
DISPLAY 0.617021 (-7855 950);
PAINT AQUA (-7855 950);
FORCEPROP 1 LAST MATERIAL CHIP
J 0
(-7685 950);
DISPLAY 0.617021 (-7685 950);
PAINT SKYBLUE (-7685 950);
FORCEPROP 1 LAST PART_NUMBER G21796-048
J 0
(-7685 900);
DISPLAY 0.617021 (-7685 900);
PAINT BLUE (-7685 900);
FORCEPROP 1 LAST PACK_TYPE 0402
J 0
(-7685 850);
DISPLAY 0.617021 (-7685 850);
PAINT SKYBLUE (-7685 850);
FORCEPROP 1 LAST VALUE 49.9K
J 0
(-7855 900);
DISPLAY 0.617021 (-7855 900);
PAINT SKYBLUE (-7855 900);
FORCEPROP 1 LAST TOLERANCE 1%
J 0
(-7855 850);
DISPLAY 0.617021 (-7855 850);
PAINT SKYBLUE (-7855 850);
FORCEPROP 1 LAST WATTAGE 1/16W
J 0
(-7860 800);
DISPLAY 0.617021 (-7860 800);
PAINT SKYBLUE (-7860 800);
FORCEPROP 0 LAST SEC 1
J 0
(-7850 1075);
DISPLAY 0.680851 (-7850 1075);
PAINT MONO (-7850 1075);
DISPLAY INVISIBLE (-7850 1075);
FORCEPROP 2 LAST SEC_TYPE 0402
J 0
(-7850 1125);
DISPLAY 1.021277 (-7850 1125);
PAINT ORANGE (-7850 1125);
DISPLAY INVISIBLE (-7850 1125);
FORCEPROP 2 LAST ROOM V_SUPER
J 0
(-7850 1075);
DISPLAY 1.021277 (-7850 1075);
PAINT ORANGE (-7850 1075);
DISPLAY INVISIBLE (-7850 1075);
FORCEPROP 2 LAST CDS_LIB mstr_discrete
J 0
(-7900 900);
PAINT MONO (-7900 900);
DISPLAY INVISIBLE (-7900 900);
FORCEPROP 0 LAST CDS_LOCATION R32W4
J 0
(-7675 1025);
DISPLAY INVISIBLE (-7675 1025);
FORCEPROP 0 LAST CDS_SEC 1
J 0
(-7675 1025);
DISPLAY INVISIBLE (-7675 1025);
FORCEPROP 1 LAST PATH I211
J 0
(-7850 1075);
DISPLAY 0.978723 (-7850 1075);
PAINT WHITE (-7850 1075);
DISPLAY INVISIBLE (-7850 1075);
FORCEADD GND..1
(-6550 1300);
FORCEPROP 3 LASTPIN (-6550 1350) SIG_NAME GND\g
J 0
(-6540 1360);
DISPLAY 0.659574 (-6540 1360);
PAINT MONO (-6540 1360);
DISPLAY INVISIBLE (-6540 1360);
FORCEPROP 1 LAST PATH I212
J 0
(-6475 1300);
DISPLAY 0.872340 (-6475 1300);
PAINT AQUA (-6475 1300);
DISPLAY INVISIBLE (-6475 1300);
FORCEPROP 1 LAST HDL_POWER GND
J 0
(-6550 1450);
DISPLAY 0.872340 (-6550 1450);
PAINT GREEN (-6550 1450);
DISPLAY INVISIBLE (-6550 1450);
FORCEPROP 2 LAST CDS_LIB mstr_symbols
J 0
(-6550 1300);
PAINT ORANGE (-6550 1300);
DISPLAY INVISIBLE (-6550 1300);
FORCEPROP 1 LAST VOLTAGE 0.0V
J 0
(-6595 1257);
DISPLAY 0.340426 (-6595 1257);
PAINT SKYBLUE (-6595 1257);
DISPLAY INVISIBLE (-6595 1257);
FORCEPROP 1 LAST SIZE 1B
J 0
(-6475 1250);
DISPLAY 0.872340 (-6475 1250);
PAINT AQUA (-6475 1250);
DISPLAY INVISIBLE (-6475 1250);
FORCEPROP 1 LAST BODY_TYPE PLUMBING
J 0
(-6595 1257);
DISPLAY 0.340426 (-6595 1257);
PAINT GREEN (-6595 1257);
DISPLAY INVISIBLE (-6595 1257);
FORCEADD LMV431AIMFX-GP..1
(-6900 1400);
FORCEPROP 2 LASTPIN (-7250 1300) $PN 2
J 2
(-7260 1310);
DISPLAY 0.808511 (-7260 1310);
PAINT ORANGE (-7260 1310);
FORCEPROP 2 LASTPIN (-7250 1500) $PN 1
J 2
(-7260 1510);
DISPLAY 0.808511 (-7260 1510);
PAINT ORANGE (-7260 1510);
FORCEPROP 2 LASTPIN (-6550 1400) $PN 3
J 0
(-6540 1410);
DISPLAY 0.808511 (-6540 1410);
PAINT ORANGE (-6540 1410);
FORCEPROP 1 LAST PART_NUMBER 74.MV431.031
J 0
(-7099 1150);
DISPLAY 0.744681 (-7099 1150);
PAINT GREEN (-7099 1150);
FORCEPROP 1 LAST VALUE LMV431AIMFX-GP
J 0
(-7099 1200);
DISPLAY 0.744681 (-7099 1200);
PAINT GREEN (-7099 1200);
FORCEPROP 1 LAST LOCATION VR32W1
J 0
(-7100 1575);
DISPLAY 0.744681 (-7100 1575);
PAINT GREEN (-7100 1575);
FORCEPROP 1 LAST PATH I213
J 0
(-6900 1400);
DISPLAY 0.744681 (-6900 1400);
PAINT GREEN (-6900 1400);
DISPLAY INVISIBLE (-6900 1400);
FORCEPROP 0 LAST CDS_SEC 1
J 0
(-7100 1625);
DISPLAY INVISIBLE (-7100 1625);
FORCEPROP 0 LAST CDS_LOCATION VR32W1
J 0
(-7100 1625);
DISPLAY INVISIBLE (-7100 1625);
FORCEPROP 2 LAST CDS_LIB w_hdl
J 0
(-6900 1400);
DISPLAY INVISIBLE (-6900 1400);
FORCEPROP 1 LAST CDS_LMAN_SYM_OUTLINE -200,150,200,-150
J 0
(-6900 1400);
DISPLAY 0.468085 (-6900 1400);
PAINT GREEN (-6900 1400);
DISPLAY INVISIBLE (-6900 1400);
FORCEPROP 1 LAST PACK_TYPE DISCRET-G5
J 0
(-6900 1400);
DISPLAY 0.744681 (-6900 1400);
PAINT GREEN (-6900 1400);
DISPLAY INVISIBLE (-6900 1400);
FORCEPROP 2 LAST SEC 1
J 0
(-7100 1625);
DISPLAY 0.680851 (-7100 1625);
PAINT MONO (-7100 1625);
DISPLAY INVISIBLE (-7100 1625);
FORCEPROP 2 LAST SEC_TYPE DISCRET-G5
J 0
(-7100 1625);
DISPLAY 1.021277 (-7100 1625);
PAINT ORANGE (-7100 1625);
DISPLAY INVISIBLE (-7100 1625);
FORCEADD RES..2
(-5450 1150);
FORCEPROP 1 LAST PACK_TYPE 0402
J 0
(-5410 975);
DISPLAY 0.617021 (-5410 975);
PAINT SKYBLUE (-5410 975);
FORCEPROP 1 LAST PART_NUMBER G21796-001
J 0
(-5410 1025);
DISPLAY 0.617021 (-5410 1025);
PAINT BLUE (-5410 1025);
FORCEPROP 1 LAST MATERIAL CHIP
J 0
(-5410 1075);
DISPLAY 0.617021 (-5410 1075);
PAINT SKYBLUE (-5410 1075);
FORCEPROP 1 LAST WATTAGE 1/16W
J 0
(-5410 1125);
DISPLAY 0.617021 (-5410 1125);
PAINT SKYBLUE (-5410 1125);
FORCEPROP 1 LAST VALUE 2.0K
J 0
(-5405 1225);
DISPLAY 0.617021 (-5405 1225);
PAINT SKYBLUE (-5405 1225);
FORCEPROP 1 LAST LOCATION R32W6
J 0
(-5405 1275);
DISPLAY 0.617021 (-5405 1275);
PAINT AQUA (-5405 1275);
FORCEPROP 1 LAST TOLERANCE 1%
J 0
(-5405 1175);
DISPLAY 0.617021 (-5405 1175);
PAINT SKYBLUE (-5405 1175);
FORCEPROP 1 LASTPIN (-5450 1250) $PN 1
J 0
(-5445 1212);
DISPLAY 0.787234 (-5445 1212);
PAINT ORANGE (-5445 1212);
FORCEPROP 1 LASTPIN (-5450 1050) $PN 2
J 0
(-5445 1060);
DISPLAY 0.787234 (-5445 1060);
PAINT ORANGE (-5445 1060);
FORCEPROP 1 LAST PATH I214
J 0
(-5400 1325);
DISPLAY 0.978723 (-5400 1325);
PAINT WHITE (-5400 1325);
DISPLAY INVISIBLE (-5400 1325);
FORCEPROP 2 LAST CDS_LOCATION R32W6
J 0
(-5405 1275);
DISPLAY 0.617021 (-5405 1275);
PAINT AQUA (-5405 1275);
DISPLAY INVISIBLE (-5405 1275);
FORCEPROP 0 LAST CDS_SEC 1
J 0
(-5400 1325);
PAINT MONO (-5400 1325);
DISPLAY INVISIBLE (-5400 1325);
FORCEPROP 0 LAST SEC 1
J 0
(-5400 1325);
DISPLAY 0.680851 (-5400 1325);
PAINT MONO (-5400 1325);
DISPLAY INVISIBLE (-5400 1325);
FORCEPROP 2 LAST SEC_TYPE 0402
J 0
(-5400 1375);
DISPLAY 1.021277 (-5400 1375);
PAINT ORANGE (-5400 1375);
DISPLAY INVISIBLE (-5400 1375);
FORCEPROP 2 LAST BOM_COST SM_CONTROLLER
J 0
(-5400 1475);
DISPLAY 1.021277 (-5400 1475);
PAINT ORANGE (-5400 1475);
DISPLAY INVISIBLE (-5400 1475);
FORCEPROP 2 LAST ROOM SMBUS
J 0
(-5400 1375);
DISPLAY 1.021277 (-5400 1375);
PAINT ORANGE (-5400 1375);
DISPLAY INVISIBLE (-5400 1375);
FORCEPROP 2 LAST CDS_LIB mstr_discrete
J 0
(-5450 1150);
PAINT ORANGE (-5450 1150);
DISPLAY INVISIBLE (-5450 1150);
FORCEADD RES..2
(-5150 1150);
FORCEPROP 1 LAST PACK_TYPE 0402
J 0
(-5110 975);
DISPLAY 0.617021 (-5110 975);
PAINT SKYBLUE (-5110 975);
FORCEPROP 1 LAST MATERIAL CHIP
J 0
(-5110 1075);
DISPLAY 0.617021 (-5110 1075);
PAINT SKYBLUE (-5110 1075);
FORCEPROP 1 LAST WATTAGE 1/16W
J 0
(-5110 1125);
DISPLAY 0.617021 (-5110 1125);
PAINT SKYBLUE (-5110 1125);
FORCEPROP 1 LAST TOLERANCE 1%
J 0
(-5105 1175);
DISPLAY 0.617021 (-5105 1175);
PAINT SKYBLUE (-5105 1175);
FORCEPROP 1 LAST VALUE 2.0K
J 0
(-5105 1225);
DISPLAY 0.617021 (-5105 1225);
PAINT SKYBLUE (-5105 1225);
FORCEPROP 1 LASTPIN (-5150 1250) $PN 1
J 0
(-5145 1212);
DISPLAY 0.787234 (-5145 1212);
PAINT ORANGE (-5145 1212);
FORCEPROP 1 LASTPIN (-5150 1050) $PN 2
J 0
(-5145 1060);
DISPLAY 0.787234 (-5145 1060);
PAINT ORANGE (-5145 1060);
FORCEPROP 1 LAST PART_NUMBER G21796-001
J 0
(-5110 1025);
DISPLAY 0.617021 (-5110 1025);
PAINT BLUE (-5110 1025);
FORCEPROP 1 LAST LOCATION R32W7
J 0
(-5105 1275);
DISPLAY 0.617021 (-5105 1275);
PAINT AQUA (-5105 1275);
FORCEPROP 1 LAST PATH I215
J 0
(-5100 1325);
DISPLAY 0.978723 (-5100 1325);
PAINT WHITE (-5100 1325);
DISPLAY INVISIBLE (-5100 1325);
FORCEPROP 2 LAST CDS_LOCATION R32W7
J 0
(-5105 1275);
DISPLAY 0.617021 (-5105 1275);
PAINT AQUA (-5105 1275);
DISPLAY INVISIBLE (-5105 1275);
FORCEPROP 0 LAST CDS_SEC 1
J 0
(-5100 1325);
PAINT MONO (-5100 1325);
DISPLAY INVISIBLE (-5100 1325);
FORCEPROP 0 LAST SEC 1
J 0
(-5100 1325);
DISPLAY 0.680851 (-5100 1325);
PAINT MONO (-5100 1325);
DISPLAY INVISIBLE (-5100 1325);
FORCEPROP 2 LAST SEC_TYPE 0402
J 0
(-5100 1375);
DISPLAY 1.021277 (-5100 1375);
PAINT ORANGE (-5100 1375);
DISPLAY INVISIBLE (-5100 1375);
FORCEPROP 2 LAST BOM_COST SM_CONTROLLER
J 0
(-5100 1475);
DISPLAY 1.021277 (-5100 1475);
PAINT ORANGE (-5100 1475);
DISPLAY INVISIBLE (-5100 1475);
FORCEPROP 2 LAST ROOM SMBUS
J 0
(-5100 1375);
DISPLAY 1.021277 (-5100 1375);
PAINT ORANGE (-5100 1375);
DISPLAY INVISIBLE (-5100 1375);
FORCEPROP 2 LAST CDS_LIB mstr_discrete
J 0
(-5150 1150);
PAINT ORANGE (-5150 1150);
DISPLAY INVISIBLE (-5150 1150);
FORCEADD RES..2
(-5750 1150);
FORCEPROP 1 LAST TOLERANCE 1%
J 0
(-5705 1175);
DISPLAY 0.617021 (-5705 1175);
PAINT SKYBLUE (-5705 1175);
FORCEPROP 1 LAST WATTAGE 1/16W
J 0
(-5710 1125);
DISPLAY 0.617021 (-5710 1125);
PAINT SKYBLUE (-5710 1125);
FORCEPROP 1 LAST LOCATION R32W5
J 0
(-5705 1275);
DISPLAY 0.617021 (-5705 1275);
PAINT AQUA (-5705 1275);
FORCEPROP 1 LAST PACK_TYPE 0402
J 0
(-5710 975);
DISPLAY 0.617021 (-5710 975);
PAINT SKYBLUE (-5710 975);
FORCEPROP 1 LAST VALUE 2.0K
J 0
(-5705 1225);
DISPLAY 0.617021 (-5705 1225);
PAINT SKYBLUE (-5705 1225);
FORCEPROP 1 LASTPIN (-5750 1250) $PN 1
J 0
(-5745 1212);
DISPLAY 0.787234 (-5745 1212);
PAINT ORANGE (-5745 1212);
FORCEPROP 1 LASTPIN (-5750 1050) $PN 2
J 0
(-5745 1060);
DISPLAY 0.787234 (-5745 1060);
PAINT ORANGE (-5745 1060);
FORCEPROP 1 LAST PART_NUMBER G21796-001
J 0
(-5710 1025);
DISPLAY 0.617021 (-5710 1025);
PAINT BLUE (-5710 1025);
FORCEPROP 1 LAST MATERIAL CHIP
J 0
(-5710 1075);
DISPLAY 0.617021 (-5710 1075);
PAINT SKYBLUE (-5710 1075);
FORCEPROP 1 LAST PATH I216
J 0
(-5700 1325);
DISPLAY 0.978723 (-5700 1325);
PAINT WHITE (-5700 1325);
DISPLAY INVISIBLE (-5700 1325);
FORCEPROP 2 LAST CDS_LOCATION R32W5
J 0
(-5705 1275);
DISPLAY 0.617021 (-5705 1275);
PAINT AQUA (-5705 1275);
DISPLAY INVISIBLE (-5705 1275);
FORCEPROP 0 LAST CDS_SEC 1
J 0
(-5700 1325);
PAINT MONO (-5700 1325);
DISPLAY INVISIBLE (-5700 1325);
FORCEPROP 0 LAST SEC 1
J 0
(-5700 1325);
DISPLAY 0.680851 (-5700 1325);
PAINT MONO (-5700 1325);
DISPLAY INVISIBLE (-5700 1325);
FORCEPROP 2 LAST SEC_TYPE 0402
J 0
(-5700 1375);
DISPLAY 1.021277 (-5700 1375);
PAINT ORANGE (-5700 1375);
DISPLAY INVISIBLE (-5700 1375);
FORCEPROP 2 LAST BOM_COST SM_CONTROLLER
J 0
(-5700 1475);
DISPLAY 1.021277 (-5700 1475);
PAINT ORANGE (-5700 1475);
DISPLAY INVISIBLE (-5700 1475);
FORCEPROP 2 LAST ROOM SMBUS
J 0
(-5700 1375);
DISPLAY 1.021277 (-5700 1375);
PAINT ORANGE (-5700 1375);
DISPLAY INVISIBLE (-5700 1375);
FORCEPROP 2 LAST CDS_LIB mstr_discrete
J 0
(-5750 1150);
PAINT ORANGE (-5750 1150);
DISPLAY INVISIBLE (-5750 1150);
FORCEADD CAP..1
(-7300 900);
FORCEPROP 1 LAST PART_NUMBER D97712-011
J 0
(-7100 900);
DISPLAY 0.617021 (-7100 900);
PAINT BLUE (-7100 900);
FORCEPROP 1 LAST LOCATION C32W5
J 0
(-7250 950);
DISPLAY 0.617021 (-7250 950);
PAINT AQUA (-7250 950);
FORCEPROP 1 LAST PACK_TYPE 0402
J 0
(-7100 850);
DISPLAY 0.617021 (-7100 850);
PAINT SKYBLUE (-7100 850);
FORCEPROP 1 LAST MATERIAL X6S
J 0
(-7100 950);
DISPLAY 0.617021 (-7100 950);
PAINT SKYBLUE (-7100 950);
FORCEPROP 1 LAST VALUE 1.0UF
J 0
(-7250 900);
DISPLAY 0.617021 (-7250 900);
PAINT SKYBLUE (-7250 900);
FORCEPROP 1 LASTPIN (-7300 1000) $PN 1
J 0
(-7290 980);
DISPLAY 0.787234 (-7290 980);
PAINT ORANGE (-7290 980);
FORCEPROP 1 LAST VOLTAGE 16V
J 0
(-7250 850);
DISPLAY 0.617021 (-7250 850);
PAINT SKYBLUE (-7250 850);
FORCEPROP 1 LAST TOLERANCE 10%
J 0
(-7250 800);
DISPLAY 0.617021 (-7250 800);
PAINT SKYBLUE (-7250 800);
FORCEPROP 1 LASTPIN (-7300 800) $PN 2
J 0
(-7290 780);
DISPLAY 0.787234 (-7290 780);
PAINT ORANGE (-7290 780);
FORCEPROP 0 LAST POP NOPOP
J 0
(-7250 750);
DISPLAY 0.638298 (-7250 750);
PAINT RED (-7250 750);
FORCEPROP 2 LAST SEC_TYPE 0402
J 0
(-7250 1100);
DISPLAY 1.021277 (-7250 1100);
PAINT ORANGE (-7250 1100);
DISPLAY INVISIBLE (-7250 1100);
FORCEPROP 2 LAST SEC 1
J 0
(-7250 1100);
DISPLAY 0.680851 (-7250 1100);
PAINT MONO (-7250 1100);
DISPLAY INVISIBLE (-7250 1100);
FORCEPROP 2 LAST CDS_LIB mstr_discrete
J 0
(-7300 900);
DISPLAY INVISIBLE (-7300 900);
FORCEPROP 1 LAST PATH I217
J 0
(-7250 1050);
DISPLAY 0.978723 (-7250 1050);
PAINT WHITE (-7250 1050);
DISPLAY INVISIBLE (-7250 1050);
FORCEPROP 0 LAST ROOM PROC_SIDEBAND
J 0
(-7250 1100);
DISPLAY 1.021277 (-7250 1100);
PAINT ORANGE (-7250 1100);
DISPLAY INVISIBLE (-7250 1100);
FORCEPROP 0 LAST BOM_COST PROC
J 0
(-7250 1100);
DISPLAY 1.021277 (-7250 1100);
PAINT ORANGE (-7250 1100);
DISPLAY INVISIBLE (-7250 1100);
FORCEADD GND..1
(-7300 700);
FORCEPROP 3 LASTPIN (-7300 750) SIG_NAME GND\g
J 0
(-7290 760);
DISPLAY 0.659574 (-7290 760);
PAINT MONO (-7290 760);
DISPLAY INVISIBLE (-7290 760);
FORCEPROP 1 LAST PATH I218
J 0
(-7225 700);
DISPLAY 0.872340 (-7225 700);
PAINT AQUA (-7225 700);
DISPLAY INVISIBLE (-7225 700);
FORCEPROP 1 LAST BODY_TYPE PLUMBING
J 0
(-7345 657);
DISPLAY 0.340426 (-7345 657);
PAINT GREEN (-7345 657);
DISPLAY INVISIBLE (-7345 657);
FORCEPROP 1 LAST SIZE 1B
J 0
(-7225 650);
DISPLAY 0.872340 (-7225 650);
PAINT AQUA (-7225 650);
DISPLAY INVISIBLE (-7225 650);
FORCEPROP 1 LAST VOLTAGE 0.0V
J 0
(-7345 657);
DISPLAY 0.340426 (-7345 657);
PAINT SKYBLUE (-7345 657);
DISPLAY INVISIBLE (-7345 657);
FORCEPROP 2 LAST CDS_LIB mstr_symbols
J 0
(-7300 700);
PAINT ORANGE (-7300 700);
DISPLAY INVISIBLE (-7300 700);
FORCEPROP 1 LAST HDL_POWER GND
J 0
(-7300 850);
DISPLAY 0.872340 (-7300 850);
PAINT GREEN (-7300 850);
DISPLAY INVISIBLE (-7300 850);
FORCEADD OFFPAGE..2
(-1150 2100);
FORCEPROP 2 LAST $XR0 185 
J 0
(-961 2100);
DISPLAY 0.638298 (-961 2100);
PAINT MONO (-961 2100);
FORCEPROP 1 LAST COMMENT_BODY TRUE
J 0
(-1195 2005);
DISPLAY 0.872340 (-1195 2005);
PAINT GREEN (-1195 2005);
DISPLAY INVISIBLE (-1195 2005);
FORCEPROP 2 LAST CDS_LIB mstr_standard
J 0
(-1150 2100);
PAINT ORANGE (-1150 2100);
DISPLAY INVISIBLE (-1150 2100);
FORCEPROP 2 LAST PATH I91
J 0
(-950 2150);
DISPLAY 1.021277 (-950 2150);
PAINT ORANGE (-950 2150);
DISPLAY INVISIBLE (-950 2150);
FORCEPROP 1 LAST OFFPAGE TRUE
J 0
(-825 1975);
DISPLAY 0.872340 (-825 1975);
PAINT GREEN (-825 1975);
DISPLAY INVISIBLE (-825 1975);
FORCEADD OFFPAGE..2
(-1150 1600);
FORCEPROP 2 LAST $XR0 185 
J 0
(-961 1600);
DISPLAY 0.638298 (-961 1600);
PAINT MONO (-961 1600);
FORCEPROP 1 LAST COMMENT_BODY TRUE
J 0
(-1195 1505);
DISPLAY 0.872340 (-1195 1505);
PAINT GREEN (-1195 1505);
DISPLAY INVISIBLE (-1195 1505);
FORCEPROP 2 LAST CDS_LIB mstr_standard
J 0
(-1150 1600);
PAINT ORANGE (-1150 1600);
DISPLAY INVISIBLE (-1150 1600);
FORCEPROP 2 LAST PATH I92
J 0
(-950 1650);
DISPLAY 1.021277 (-950 1650);
PAINT ORANGE (-950 1650);
DISPLAY INVISIBLE (-950 1650);
FORCEPROP 1 LAST OFFPAGE TRUE
J 0
(-825 1475);
DISPLAY 0.872340 (-825 1475);
PAINT GREEN (-825 1475);
DISPLAY INVISIBLE (-825 1475);
FORCEADD OFFPAGE..4
(-1150 1175);
FORCEPROP 2 LAST $XR0 185 
J 0
(-964 1175);
DISPLAY 0.638298 (-964 1175);
PAINT MONO (-964 1175);
FORCEPROP 1 LAST COMMENT_BODY TRUE
J 0
(-1175 1075);
DISPLAY 0.872340 (-1175 1075);
PAINT GREEN (-1175 1075);
DISPLAY INVISIBLE (-1175 1075);
FORCEPROP 2 LAST CDS_LIB mstr_standard
J 0
(-1150 1175);
PAINT ORANGE (-1150 1175);
DISPLAY INVISIBLE (-1150 1175);
FORCEPROP 2 LAST PATH I93
J 0
(-950 1225);
DISPLAY 1.021277 (-950 1225);
PAINT ORANGE (-950 1225);
DISPLAY INVISIBLE (-950 1225);
FORCEPROP 1 LAST OFFPAGE TRUE
J 0
(-825 1050);
DISPLAY 0.872340 (-825 1050);
PAINT GREEN (-825 1050);
DISPLAY INVISIBLE (-825 1050);
FORCEADD OFFPAGE..4
(-1150 750);
FORCEPROP 2 LAST $XR0 185 
J 0
(-964 750);
DISPLAY 0.638298 (-964 750);
PAINT MONO (-964 750);
FORCEPROP 1 LAST COMMENT_BODY TRUE
J 0
(-1175 650);
DISPLAY 0.872340 (-1175 650);
PAINT GREEN (-1175 650);
DISPLAY INVISIBLE (-1175 650);
FORCEPROP 2 LAST CDS_LIB mstr_standard
J 0
(-1150 750);
PAINT ORANGE (-1150 750);
DISPLAY INVISIBLE (-1150 750);
FORCEPROP 2 LAST PATH I94
J 0
(-950 800);
DISPLAY 1.021277 (-950 800);
PAINT ORANGE (-950 800);
DISPLAY INVISIBLE (-950 800);
FORCEPROP 1 LAST OFFPAGE TRUE
J 0
(-825 625);
DISPLAY 0.872340 (-825 625);
PAINT GREEN (-825 625);
DISPLAY INVISIBLE (-825 625);
FORCEADD CAP..2
(-2575 1825);
FORCEPROP 1 LAST VOLTAGE 16V
J 0
(-2325 1825);
DISPLAY 0.617021 (-2325 1825);
PAINT SKYBLUE (-2325 1825);
FORCEPROP 1 LAST MATERIAL X7R
J 0
(-2425 1825);
DISPLAY 0.617021 (-2425 1825);
PAINT SKYBLUE (-2425 1825);
FORCEPROP 1 LASTPIN (-2675 1825) $PN 1
J 0
(-2685 1840);
DISPLAY 0.617021 (-2685 1840);
PAINT ORANGE (-2685 1840);
FORCEPROP 1 LAST PACK_TYPE 0402
J 2
(-2100 1825);
DISPLAY 0.617021 (-2100 1825);
PAINT SKYBLUE (-2100 1825);
FORCEPROP 1 LAST PART_NUMBER A36096-155
J 2
(-1825 1825);
DISPLAY 0.617021 (-1825 1825);
PAINT BLUE (-1825 1825);
FORCEPROP 1 LASTPIN (-2475 1825) $PN 2
J 0
(-2490 1840);
DISPLAY 0.617021 (-2490 1840);
PAINT ORANGE (-2490 1840);
FORCEPROP 1 LAST LOCATION C8F7
J 0
(-3075 1825);
DISPLAY 0.617021 (-3075 1825);
PAINT AQUA (-3075 1825);
FORCEPROP 1 LAST VALUE 0.22UF
J 1
(-2850 1825);
DISPLAY 0.617021 (-2850 1825);
PAINT SKYBLUE (-2850 1825);
FORCEPROP 0 LAST GROUP M2_PCIE
J 0
(-2700 1875);
DISPLAY 0.638298 (-2700 1875);
PAINT BROWN (-2700 1875);
DISPLAY BOTH (-2700 1875);
FORCEPROP 1 LAST TOLERANCE 10%
J 2
(-2700 1825);
DISPLAY 0.617021 (-2700 1825);
PAINT SKYBLUE (-2700 1825);
FORCEPROP 2 LAST CDS_LOCATION C8F7
J 0
(-3075 1825);
DISPLAY 0.617021 (-3075 1825);
PAINT AQUA (-3075 1825);
DISPLAY INVISIBLE (-3075 1825);
FORCEPROP 2 LAST CDS_LIB mstr_discrete
J 0
(-2575 1825);
PAINT ORANGE (-2575 1825);
DISPLAY INVISIBLE (-2575 1825);
FORCEPROP 0 LAST ROOM M_2
J 0
(-1825 1875);
DISPLAY 1.021277 (-1825 1875);
PAINT ORANGE (-1825 1875);
DISPLAY INVISIBLE (-1825 1875);
FORCEPROP 0 LAST BOM_COST ST_FLASH
J 0
(-1825 1925);
DISPLAY 1.021277 (-1825 1925);
PAINT ORANGE (-1825 1925);
DISPLAY INVISIBLE (-1825 1925);
FORCEPROP 2 LAST SEC_TYPE 0402
J 0
(-2575 2075);
DISPLAY 1.021277 (-2575 2075);
PAINT ORANGE (-2575 2075);
DISPLAY INVISIBLE (-2575 2075);
FORCEPROP 2 LAST SEC 1
J 0
(-2575 2075);
DISPLAY 0.680851 (-2575 2075);
PAINT MONO (-2575 2075);
DISPLAY INVISIBLE (-2575 2075);
FORCEPROP 1 LAST PATH I96
J 0
(-2575 2025);
DISPLAY 0.978723 (-2575 2025);
PAINT WHITE (-2575 2025);
DISPLAY INVISIBLE (-2575 2025);
FORCEADD CAD_NOTE..1
(-2600 4850);
FORCEPROP 0 LAST L1 PLACE CLOSE TO PINS 12,14,16,18
J 0
(-2750 4750);
DISPLAY 1.021277 (-2750 4750);
PAINT ORANGE (-2750 4750);
FORCEPROP 1 LAST COMMENT_BODY TRUE
J 0
(-2575 4950);
DISPLAY 0.978723 (-2575 4950);
PAINT ORANGE (-2575 4950);
DISPLAY INVISIBLE (-2575 4950);
FORCEPROP 2 LAST CDS_LIB mstr_symbols
J 0
(-2600 4850);
PAINT MONO (-2600 4850);
DISPLAY INVISIBLE (-2600 4850);
FORCEADD DESIGN_NOTE..1
(-5200 1950);
FORCEPROP 1 LAST COMMENT_BODY TRUE
J 0
(-5175 2050);
DISPLAY 0.978723 (-5175 2050);
PAINT ORANGE (-5175 2050);
DISPLAY INVISIBLE (-5175 2050);
FORCEPROP 2 LAST CDS_LIB mstr_symbols
J 0
(-5200 1950);
PAINT ORANGE (-5200 1950);
DISPLAY INVISIBLE (-5200 1950);
FORCEADD INTEL_CORP_BPAGE..1
(-125 0);
FORCEPROP 1 LAST CDS_CON_LAST_MODIFIED Fri Jun 16 17:49:08 2017
J 0
(-1550 325);
PAINT GREEN (-1550 325);
DISPLAY INVISIBLE (-1550 325);
FORCEPROP 1 LAST CUSTOM_TXT_CDS <CURRENT_DESIGN_SHEET> OF <TOTAL_DESIGN_SHEETS>
J 0
(-625 25);
PAINT ORANGE (-625 25);
FORCEPROP 2 LAST CUSTOM_TXT_CDS <XR_PAGE_TITLE>
J 0
(-8015 5250);
DISPLAY 0.638298 (-8015 5250);
PAINT PINK (-8015 5250);
DISPLAY INVISIBLE (-8015 5250);
FORCEPROP 2 LAST CUSTOM_TXT_CDS <CON_LAST_MODIFIED>
J 0
(-4125 100);
PAINT ORANGE (-4125 100);
FORCEPROP 1 LAST SCH_TITLE M.2 CONNECTOR
J 0
(-8075 50);
DISPLAY 1.212766 (-8075 50);
PAINT ORANGE (-8075 50);
FORCEPROP 1 LAST COMMENT_BODY TRUE
J 0
(-113 12);
DISPLAY 0.468085 (-113 12);
PAINT GREEN (-113 12);
DISPLAY INVISIBLE (-113 12);
FORCEPROP 2 LAST PAGE_BORDER TRUE
J 0
(-8015 5250);
DISPLAY 0.617021 (-8015 5250);
PAINT PINK (-8015 5250);
DISPLAY INVISIBLE (-8015 5250);
FORCEPROP 2 LAST CDS_LIB mstr_symbols
J 0
(-125 0);
PAINT ORANGE (-125 0);
DISPLAY INVISIBLE (-125 0);
FORCEPROP 2 LAST CDS_XR_PAGE_TITLE CR-185 : @BASEBOARD_FAB2_LIB.BASEBOARD_FAB2(SCH_1):PAGE185
J 0
(-8015 5250);
DISPLAY 0.638298 (-8015 5250);
PAINT PINK (-8015 5250);
DISPLAY INVISIBLE (-8015 5250);
FORCEADD CAD_NOTE..1
(-5225 2225);
FORCEPROP 0 LAST L1 PLACE CAP NEAR
J 0
(-5375 2100);
DISPLAY 1.021277 (-5375 2100);
PAINT ORANGE (-5375 2100);
FORCEPROP 0 LAST L2 74LVC1G07 POWER PIN
J 0
(-5375 2025);
DISPLAY 1.021277 (-5375 2025);
PAINT ORANGE (-5375 2025);
FORCEPROP 1 LAST COMMENT_BODY TRUE
J 0
(-5200 2325);
DISPLAY 0.978723 (-5200 2325);
PAINT ORANGE (-5200 2325);
DISPLAY INVISIBLE (-5200 2325);
FORCEPROP 2 LAST CDS_LIB mstr_symbols
J 0
(-5225 2225);
PAINT ORANGE (-5225 2225);
DISPLAY INVISIBLE (-5225 2225);
FORCEADD CAD_NOTE..1
(-1200 4850);
FORCEPROP 0 LAST L1 PLACE CLOSE TO PINS 70,72,74
J 0
(-1350 4750);
DISPLAY 1.021277 (-1350 4750);
PAINT ORANGE (-1350 4750);
FORCEPROP 1 LAST COMMENT_BODY TRUE
J 0
(-1175 4950);
DISPLAY 0.978723 (-1175 4950);
PAINT ORANGE (-1175 4950);
DISPLAY INVISIBLE (-1175 4950);
FORCEPROP 2 LAST CDS_LIB mstr_symbols
J 0
(-1200 4850);
PAINT MONO (-1200 4850);
DISPLAY INVISIBLE (-1200 4850);
FORCEADD CAD_NOTE..1
(-3950 4850);
FORCEPROP 0 LAST L1 PLACE CLOSE TO PINS 2&4
J 0
(-4100 4750);
DISPLAY 1.021277 (-4100 4750);
PAINT ORANGE (-4100 4750);
FORCEPROP 1 LAST COMMENT_BODY TRUE
J 0
(-3925 4950);
DISPLAY 0.978723 (-3925 4950);
PAINT ORANGE (-3925 4950);
DISPLAY INVISIBLE (-3925 4950);
FORCEPROP 2 LAST CDS_LIB mstr_symbols
J 0
(-3950 4850);
PAINT MONO (-3950 4850);
DISPLAY INVISIBLE (-3950 4850);
WIRE 16 -1 (-5500 2850)(-5500 2800);
WIRE 16 -1 (-4400 2950)(-4400 2900);
WIRE 16 -1 (-4500 2075)(-4500 2150);
WIRE 16 -1 (-4500 1875)(-4500 1800);
WIRE 16 -1 (-4250 4425)(-4250 4400);
WIRE 16 -1 (-4000 4425)(-4250 4425);
WIRE 16 -1 (-4250 4475)(-4250 4425);
WIRE 16 -1 (-3750 4425)(-4000 4425);
WIRE 16 -1 (-4000 4475)(-4000 4425);
WIRE 16 -1 (-3750 4475)(-3750 4425);
WIRE 16 -1 (-4250 4725)(-4250 4750);
WIRE 16 -1 (-4250 4725)(-4000 4725);
WIRE 16 -1 (-4250 4675)(-4250 4725);
WIRE 16 -1 (-4000 4725)(-3750 4725);
WIRE 16 -1 (-4000 4725)(-4000 4675);
WIRE 16 -1 (-3750 4725)(-3750 4675);
WIRE 16 -1 (-2925 4725)(-2925 4750);
WIRE 16 -1 (-2925 4725)(-2675 4725);
WIRE 16 -1 (-2925 4675)(-2925 4725);
WIRE 16 -1 (-2675 4725)(-2425 4725);
WIRE 16 -1 (-2675 4725)(-2675 4675);
WIRE 16 -1 (-2425 4725)(-2425 4675);
WIRE 16 -1 (-2925 4425)(-2925 4400);
WIRE 16 -1 (-2675 4425)(-2925 4425);
WIRE 16 -1 (-2925 4475)(-2925 4425);
WIRE 16 -1 (-2425 4425)(-2675 4425);
WIRE 16 -1 (-2675 4475)(-2675 4425);
WIRE 16 -1 (-2425 4475)(-2425 4425);
WIRE 16 -1 (-1450 4725)(-1450 4750);
WIRE 16 -1 (-1450 4725)(-1200 4725);
WIRE 16 -1 (-1450 4675)(-1450 4725);
WIRE 16 -1 (-1200 4725)(-950 4725);
WIRE 16 -1 (-1200 4725)(-1200 4675);
WIRE 16 -1 (-950 4725)(-950 4675);
WIRE 16 -1 (-1450 4425)(-1450 4400);
WIRE 16 -1 (-1200 4425)(-1450 4425);
WIRE 16 -1 (-1450 4475)(-1450 4425);
WIRE 16 -1 (-950 4425)(-1200 4425);
WIRE 16 -1 (-1200 4475)(-1200 4425);
WIRE 16 -1 (-950 4475)(-950 4425);
WIRE 16 -1 (-8000 3650)(-8000 3600);
WIRE 16 -1 (-6000 2650)(-6000 2600);
WIRE 16 -1 (-6000 2800)(-6000 2650);
WIRE 16 -1 (-6150 2650)(-6000 2650);
WIRE 16 -1 (-6000 2850)(-6000 2800);
WIRE 16 -1 (-6150 2800)(-6000 2800);
WIRE 16 -1 (-6000 2900)(-6000 2850);
WIRE 16 -1 (-6150 2850)(-6000 2850);
WIRE 16 -1 (-6150 2900)(-6000 2900);
WIRE 16 -1 (-5900 4650)(-5900 4600);
WIRE 16 -1 (-6000 4650)(-5900 4650);
WIRE 16 -1 (-6000 4650)(-6000 4550);
WIRE 16 -1 (-6150 4650)(-6000 4650);
WIRE 16 -1 (-6000 4450)(-6000 4550);
WIRE 16 -1 (-6000 4550)(-6150 4550);
WIRE 16 -1 (-6150 4450)(-6000 4450);
WIRE 16 -1 (-6150 4300)(-6000 4300);
WIRE 16 -1 (-6150 4150)(-6000 4150);
WIRE 16 -1 (-6150 4000)(-6000 4000);
WIRE 16 -1 (-6150 3850)(-6000 3850);
WIRE 16 -1 (-6150 3700)(-6000 3700);
WIRE 16 -1 (-6150 3550)(-6000 3550);
WIRE 16 -1 (-6150 3400)(-6000 3400);
WIRE 16 -1 (-6150 3250)(-6000 3250);
WIRE 16 -1 (-6150 3100)(-6000 3100);
WIRE 16 -1 (-7550 4450)(-7550 4500);
WIRE 16 -1 (-7550 4400)(-7550 4450);
WIRE 16 -1 (-6750 4450)(-7550 4450);
WIRE 16 -1 (-7550 4200)(-7550 4400);
WIRE 16 -1 (-6750 4400)(-7550 4400);
WIRE 16 -1 (-7550 4150)(-7550 4200);
WIRE 16 -1 (-7550 4200)(-6750 4200);
WIRE 16 -1 (-7550 4100)(-7550 4150);
WIRE 16 -1 (-7550 4150)(-6750 4150);
WIRE 16 -1 (-7550 4050)(-7550 4100);
WIRE 16 -1 (-7550 4100)(-6750 4100);
WIRE 16 -1 (-7550 4050)(-6750 4050);
WIRE 16 -1 (-7550 2950)(-7550 2900);
WIRE 16 -1 (-7550 2900)(-7550 2850);
WIRE 16 -1 (-6750 2900)(-7550 2900);
WIRE 16 -1 (-7550 2850)(-7550 2800);
WIRE 16 -1 (-6750 2850)(-7550 2850);
WIRE 16 -1 (-7550 2800)(-6750 2800);
WIRE 16 -1 (-2450 3100)(-2450 3050);
WIRE 16 -1 (-2100 2825)(-2100 2775);
WIRE 16 -1 (-2050 2825)(-2100 2825);
WIRE 16 -1 (-2100 3600)(-2100 3550);
WIRE 16 -1 (-2050 3600)(-2100 3600);
WIRE 16 -1 (-1150 3050)(-1150 3100);
WIRE 16 -1 (-1150 3400)(-1150 3350);
WIRE 16 -1 (-1150 3350)(-1250 3350);
WIRE 16 -1 (-1150 3350)(-1150 3300);
WIRE 16 -1 (-1250 2975)(-1250 3350);
WIRE 16 -1 (-1400 2975)(-1250 2975);
WIRE 16 -1 (-1200 3850)(-1200 3900);
WIRE 16 -1 (-850 3350)(-850 3300);
WIRE 16 -1 (-1300 4175)(-1300 4125);
WIRE 16 -1 (-1300 3750)(-1300 4125);
WIRE 16 -1 (-1300 4125)(-1200 4125);
WIRE 16 -1 (-1200 4125)(-1200 4100);
WIRE 16 -1 (-1400 3750)(-1300 3750);
WIRE 16 -1 (-2450 3875)(-2450 3825);
WIRE 16 -1 (-7800 1250)(-7800 1225);
WIRE 16 -1 (-7800 2100)(-7800 2050);
WIRE 16 -1 (-7900 800)(-7900 750);
WIRE 16 -1 (-6550 1400)(-6550 1350);
WIRE 16 -1 (-7300 800)(-7300 750);
WIRE 16 -1 (-7450 3500)(-6750 3500);
FORCEPROP 2 LAST SIG_NAME SMB_M2_SCL
J 0
(-7435 3510);
DISPLAY 0.638298 (-7435 3510);
PAINT ORANGE (-7435 3510);
FORCEPROP 2 LASTPROP $XR0 185 
J 0
(-7756 3500);
DISPLAY 0.638298 (-7756 3500);
PAINT MONO (-7756 3500);
WIRE 16 -1 (-7450 4250)(-6750 4250);
FORCEPROP 0 LAST SIG_NAME TP_LED_M2_ACT_N
J 0
(-7450 4260);
DISPLAY 0.617021 (-7450 4260);
PAINT ORANGE (-7450 4260);
FORCEPROP 2 LASTPROP $XRERR UNIQUE?
J 0
(-7690 4250);
DISPLAY 0.638298 (-7690 4250);
PAINT MONO (-7690 4250);
DISPLAY INVISIBLE (-7690 4250);
WIRE 3 682 (-6850 2500)(-6050 2500);
WIRE 3 682 (-6850 4800)(-6850 2500);
WIRE 3 682 (-6050 2500)(-6050 4800);
WIRE 3 682 (-6050 4800)(-6850 4800);
WIRE 3 682 (-150 4300)(-150 2450);
WIRE 3 682 (-3200 4300)(-150 4300);
WIRE 3 682 (-150 2450)(-3200 2450);
WIRE 3 682 (-3200 2450)(-3200 4300);
WIRE 16 -1 (-2500 1375)(-1775 1375);
WIRE 16 -1 (-1775 1375)(-1775 1600);
WIRE 16 -1 (-1775 1600)(-1200 1600);
FORCEPROP 2 LAST SIG_NAME P3E_PCH_M2_SATA6G_TX_R_DN
J 2
(-1225 1610);
DISPLAY 0.617021 (-1225 1610);
PAINT ORANGE (-1225 1610);
WIRE 16 -1 (-2500 1600)(-1775 1600);
WIRE 16 -1 (-3525 1175)(-2700 1175);
FORCEPROP 2 LAST SIG_NAME SATA6G_S0_RX_DP
J 0
(-3485 1185);
DISPLAY 0.617021 (-3485 1185);
PAINT ORANGE (-3485 1185);
WIRE 16 -1 (-3525 750)(-2675 750);
FORCEPROP 2 LAST SIG_NAME SATA6G_S0_RX_DN
J 0
(-3485 760);
DISPLAY 0.617021 (-3485 760);
PAINT ORANGE (-3485 760);
WIRE 16 -1 (-1400 2825)(-1325 2825);
WIRE 16 -1 (-850 3600)(-850 3550);
WIRE 16 -1 (-1325 3600)(-1325 2825);
WIRE 16 -1 (-1400 3600)(-1325 3600);
WIRE 16 -1 (-1325 3600)(-850 3600);
FORCEPROP 2 LAST SIG_NAME PD_SMB_M2_EN
J 0
(-1250 3610);
DISPLAY 0.617021 (-1250 3610);
PAINT ORANGE (-1250 3610);
FORCEPROP 2 LASTPROP $XRERR UNIQUE?
J 0
(-1490 3610);
DISPLAY 0.638298 (-1490 3610);
PAINT MONO (-1490 3610);
DISPLAY INVISIBLE (-1490 3610);
WIRE 16 -1 (-2050 3700)(-2575 3700);
FORCEPROP 2 LAST SIG_NAME SMB_M2_ALT_R_N
J 0
(-2525 3710);
DISPLAY 0.617021 (-2525 3710);
PAINT ORANGE (-2525 3710);
FORCEPROP 2 LASTPROP $XRERR UNIQUE?
J 0
(-2765 3710);
DISPLAY 0.638298 (-2765 3710);
PAINT MONO (-2765 3710);
DISPLAY INVISIBLE (-2765 3710);
WIRE 16 -1 (-2450 3350)(-2450 3300);
WIRE 16 -1 (-2450 3350)(-2150 3350);
FORCEPROP 2 LAST SIG_NAME P1V8_M2
J 0
(-2435 3360);
DISPLAY 1.021277 (-2435 3360);
PAINT ORANGE (-2435 3360);
FORCEPROP 2 LASTPROP $XR0 185 
J 0
(-2561 3360);
DISPLAY 0.638298 (-2561 3360);
PAINT MONO (-2561 3360);
WIRE 16 -1 (-2150 2975)(-2150 3350);
WIRE 16 -1 (-2050 2975)(-2150 2975);
WIRE 16 -1 (-675 2875)(-1400 2875);
FORCEPROP 0 LAST SIG_NAME SMB_OCP_LAN_STBY_LVC3_SDA
J 0
(-1300 2885);
DISPLAY 0.617021 (-1300 2885);
PAINT ORANGE (-1300 2885);
WIRE 16 -1 (-7800 1800)(-7800 1750);
WIRE 16 -1 (-7800 1850)(-7800 1800);
WIRE 16 -1 (-7800 1800)(-7900 1800);
WIRE 16 -1 (-7900 1050)(-7900 1000);
WIRE 16 -1 (-7900 1800)(-7900 1050);
WIRE 16 -1 (-7300 1000)(-7300 1050);
WIRE 16 -1 (-7900 1050)(-7300 1050);
WIRE 16 -1 (-7300 1050)(-6800 1050);
FORCEPROP 2 LAST SIG_NAME P1V8_M2
J 0
(-7185 1060);
DISPLAY 1.021277 (-7185 1060);
PAINT ORANGE (-7185 1060);
FORCEPROP 2 LASTPROP $XR0 185 
J 0
(-6770 1050);
DISPLAY 0.638298 (-6770 1050);
PAINT MONO (-6770 1050);
WIRE 16 -1 (-7300 1300)(-7300 1050);
WIRE 16 -1 (-7250 1300)(-7300 1300);
WIRE 3 682 (-4450 650)(-4450 1550);
WIRE 3 682 (-4450 1550)(-6400 1550);
WIRE 3 682 (-8000 650)(-4450 650);
WIRE 3 682 (-8000 2300)(-8000 650);
WIRE 3 682 (-6400 1550)(-6400 2300);
WIRE 3 682 (-6400 2300)(-8000 2300);
WIRE 16 -1 (-3525 1600)(-2700 1600);
FORCEPROP 2 LAST SIG_NAME SATA6G_S0_TX_DN
J 0
(-3485 1610);
DISPLAY 0.617021 (-3485 1610);
PAINT ORANGE (-3485 1610);
WIRE 16 -1 (-2700 950)(-3525 950);
FORCEPROP 2 LAST SIG_NAME P3E_PCH_RX_0_DP
J 0
(-3485 960);
DISPLAY 0.617021 (-3485 960);
PAINT ORANGE (-3485 960);
WIRE 3 682 (-7650 3250)(-7650 2500);
WIRE 3 682 (-6000 3000)(-5900 3000);
WIRE 16 -1 (-6750 4350)(-7450 4350);
FORCEPROP 2 LAST SIG_NAME NC_M2<0>
J 0
(-7435 4360);
DISPLAY 0.617021 (-7435 4360);
PAINT ORANGE (-7435 4360);
FORCEPROP 2 LASTPROP $XRERR UNIQUE?
J 0
(-7690 4350);
DISPLAY 0.638298 (-7690 4350);
PAINT MONO (-7690 4350);
DISPLAY INVISIBLE (-7690 4350);
WIRE 16 -1 (-6750 4300)(-7450 4300);
FORCEPROP 2 LAST SIG_NAME NC_M2<1>
J 0
(-7435 4310);
DISPLAY 0.617021 (-7435 4310);
PAINT ORANGE (-7435 4310);
FORCEPROP 2 LASTPROP $XRERR UNIQUE?
J 0
(-7690 4300);
DISPLAY 0.638298 (-7690 4300);
PAINT MONO (-7690 4300);
DISPLAY INVISIBLE (-7690 4300);
WIRE 16 -1 (-7450 2950)(-6750 2950);
FORCEPROP 0 LAST SIG_NAME TP_M2_32M_SUSCLK
J 0
(-7450 2960);
DISPLAY 0.617021 (-7450 2960);
PAINT ORANGE (-7450 2960);
FORCEPROP 2 LASTPROP $XRERR UNIQUE?
J 0
(-7690 2950);
DISPLAY 0.638298 (-7690 2950);
PAINT MONO (-7690 2950);
DISPLAY INVISIBLE (-7690 2950);
WIRE 16 -1 (-6750 3150)(-7750 3150);
FORCEPROP 0 LAST SIG_NAME FM_PE_M2_WAKE_N
J 0
(-7450 3160);
DISPLAY 0.617021 (-7450 3160);
PAINT ORANGE (-7450 3160);
WIRE 16 -1 (-2050 2875)(-2525 2875);
FORCEPROP 2 LAST SIG_NAME SMB_M2_SDA_R
J 0
(-2510 2885);
DISPLAY 0.617021 (-2510 2885);
PAINT ORANGE (-2510 2885);
FORCEPROP 2 LASTPROP $XRERR UNIQUE?
J 0
(-2750 2885);
DISPLAY 0.638298 (-2750 2885);
PAINT MONO (-2750 2885);
DISPLAY INVISIBLE (-2750 2885);
WIRE 16 -1 (-4750 4250)(-3550 4250);
FORCEPROP 2 LAST SIG_NAME P3E_PCH_M2_TX_DN<3>
J 2
(-3575 4260);
DISPLAY 0.617021 (-3575 4260);
PAINT ORANGE (-3575 4260);
WIRE 16 -1 (-4950 4250)(-6150 4250);
FORCEPROP 2 LAST SIG_NAME P3E_PCH_M2_TX_C_DN<3>
J 0
(-5900 4260);
DISPLAY 0.617021 (-5900 4260);
PAINT ORANGE (-5900 4260);
FORCEPROP 2 LASTPROP $XRERR UNIQUE?
J 0
(-6140 4260);
DISPLAY 0.638298 (-6140 4260);
PAINT MONO (-6140 4260);
DISPLAY INVISIBLE (-6140 4260);
WIRE 16 -1 (-4750 4200)(-3550 4200);
FORCEPROP 2 LAST SIG_NAME P3E_PCH_M2_TX_DP<3>
J 2
(-3575 4210);
DISPLAY 0.617021 (-3575 4210);
PAINT ORANGE (-3575 4210);
WIRE 16 -1 (-4950 4200)(-6150 4200);
FORCEPROP 2 LAST SIG_NAME P3E_PCH_M2_TX_C_DP<3>
J 0
(-5900 4210);
DISPLAY 0.617021 (-5900 4210);
PAINT ORANGE (-5900 4210);
FORCEPROP 2 LASTPROP $XRERR UNIQUE?
J 0
(-6140 4210);
DISPLAY 0.638298 (-6140 4210);
PAINT MONO (-6140 4210);
DISPLAY INVISIBLE (-6140 4210);
WIRE 16 -1 (-5450 4400)(-6150 4400);
FORCEPROP 2 LAST SIG_NAME P3E_PCH_M2_RX_DN<3>
J 2
(-5475 4410);
DISPLAY 0.617021 (-5475 4410);
PAINT ORANGE (-5475 4410);
WIRE 16 -1 (-6150 4350)(-5450 4350);
FORCEPROP 2 LAST SIG_NAME P3E_PCH_M2_RX_DP<3>
J 2
(-5475 4360);
DISPLAY 0.617021 (-5475 4360);
PAINT ORANGE (-5475 4360);
WIRE 16 -1 (-4950 3900)(-6150 3900);
FORCEPROP 2 LAST SIG_NAME P3E_PCH_M2_TX_C_DP<2>
J 0
(-5900 3910);
DISPLAY 0.617021 (-5900 3910);
PAINT ORANGE (-5900 3910);
FORCEPROP 2 LASTPROP $XRERR UNIQUE?
J 0
(-6140 3910);
DISPLAY 0.638298 (-6140 3910);
PAINT MONO (-6140 3910);
DISPLAY INVISIBLE (-6140 3910);
WIRE 16 -1 (-4750 3950)(-3550 3950);
FORCEPROP 2 LAST SIG_NAME P3E_PCH_M2_TX_DN<2>
J 2
(-3575 3960);
DISPLAY 0.617021 (-3575 3960);
PAINT ORANGE (-3575 3960);
WIRE 16 -1 (-4950 3950)(-6150 3950);
FORCEPROP 2 LAST SIG_NAME P3E_PCH_M2_TX_C_DN<2>
J 0
(-5900 3960);
DISPLAY 0.617021 (-5900 3960);
PAINT ORANGE (-5900 3960);
FORCEPROP 2 LASTPROP $XRERR UNIQUE?
J 0
(-6140 3960);
DISPLAY 0.638298 (-6140 3960);
PAINT MONO (-6140 3960);
DISPLAY INVISIBLE (-6140 3960);
WIRE 16 -1 (-6150 3500)(-5100 3500);
FORCEPROP 2 LAST SIG_NAME P3E_PCH_M2_SATA6G_RX_R_DP
J 0
(-5900 3510);
DISPLAY 0.617021 (-5900 3510);
PAINT ORANGE (-5900 3510);
WIRE 16 -1 (-6150 3350)(-5100 3350);
FORCEPROP 2 LAST SIG_NAME P3E_PCH_M2_SATA6G_TX_R_DN
J 0
(-5900 3360);
DISPLAY 0.617021 (-5900 3360);
PAINT ORANGE (-5900 3360);
WIRE 16 -1 (-6150 3300)(-5100 3300);
FORCEPROP 2 LAST SIG_NAME P3E_PCH_M2_SATA6G_TX_R_DP
J 0
(-5900 3310);
DISPLAY 0.617021 (-5900 3310);
PAINT ORANGE (-5900 3310);
WIRE 16 -1 (-6150 3200)(-5100 3200);
FORCEPROP 0 LAST SIG_NAME CLK_100M_M2_DN
J 0
(-5900 3210);
DISPLAY 0.617021 (-5900 3210);
PAINT ORANGE (-5900 3210);
WIRE 16 -1 (-6150 3450)(-5100 3450);
FORCEPROP 2 LAST SIG_NAME P3E_PCH_M2_SATA6G_RX_R_DN
J 0
(-5900 3460);
DISPLAY 0.617021 (-5900 3460);
PAINT ORANGE (-5900 3460);
WIRE 16 -1 (-4950 3650)(-6150 3650);
FORCEPROP 2 LAST SIG_NAME P3E_PCH_M2_TX_C_DN<1>
J 0
(-5900 3660);
DISPLAY 0.617021 (-5900 3660);
PAINT ORANGE (-5900 3660);
FORCEPROP 2 LASTPROP $XRERR UNIQUE?
J 0
(-6140 3660);
DISPLAY 0.638298 (-6140 3660);
PAINT MONO (-6140 3660);
DISPLAY INVISIBLE (-6140 3660);
WIRE 16 -1 (-4150 2500)(-3450 2500);
FORCEPROP 0 LAST SIG_NAME FM_SSATA_PCIE_M2_SEL
J 0
(-4085 2510);
DISPLAY 0.617021 (-4085 2510);
PAINT ORANGE (-4085 2510);
WIRE 16 -1 (-5500 2500)(-5250 2500);
WIRE 16 -1 (-5500 2600)(-5500 2500);
WIRE 16 -1 (-5950 2500)(-5500 2500);
FORCEPROP 0 LAST SIG_NAME FM_M2_SSD_PEDET
J 0
(-5900 2510);
DISPLAY 0.617021 (-5900 2510);
PAINT ORANGE (-5900 2510);
FORCEPROP 2 LASTPROP $XRERR UNIQUE?
J 0
(-6140 2510);
DISPLAY 0.638298 (-6140 2510);
PAINT MONO (-6140 2510);
DISPLAY INVISIBLE (-6140 2510);
WIRE 16 -1 (-5950 2950)(-5950 2500);
WIRE 16 -1 (-6150 2950)(-5950 2950);
WIRE 16 -1 (-2700 1375)(-3525 1375);
FORCEPROP 2 LAST SIG_NAME P3E_PCH_TX_0_DN
J 0
(-3510 1385);
DISPLAY 0.617021 (-3510 1385);
PAINT ORANGE (-3510 1385);
WIRE 16 -1 (-6150 3150)(-5100 3150);
FORCEPROP 0 LAST SIG_NAME CLK_100M_M2_DP
J 0
(-5900 3160);
DISPLAY 0.617021 (-5900 3160);
PAINT ORANGE (-5900 3160);
WIRE 16 -1 (-4825 900)(-5150 900);
FORCEPROP 2 LAST SIG_NAME SMB_M2_ALT_N
J 0
(-5100 910);
DISPLAY 0.617021 (-5100 910);
PAINT ORANGE (-5100 910);
FORCEPROP 2 LASTPROP $XR0 185 
J 0
(-4735 900);
DISPLAY 0.638298 (-4735 900);
PAINT MONO (-4735 900);
WIRE 16 -1 (-5150 1050)(-5150 900);
WIRE 16 -1 (-750 3700)(-1400 3700);
FORCEPROP 0 LAST SIG_NAME IRQ_MEZZ_LAN_ALERT_N
J 0
(-1260 3710);
DISPLAY 0.617021 (-1260 3710);
PAINT ORANGE (-1260 3710);
WIRE 16 -1 (-2450 4125)(-2450 4075);
WIRE 16 -1 (-2450 4125)(-2150 4125);
FORCEPROP 2 LAST SIG_NAME P1V8_M2
J 0
(-2460 4135);
DISPLAY 1.021277 (-2460 4135);
PAINT ORANGE (-2460 4135);
FORCEPROP 2 LASTPROP $XR0 185 
J 0
(-2586 4135);
DISPLAY 0.638298 (-2586 4135);
PAINT MONO (-2586 4135);
WIRE 16 -1 (-2150 3750)(-2150 4125);
WIRE 16 -1 (-2050 3750)(-2150 3750);
WIRE 16 -1 (-3150 3700)(-2775 3700);
FORCEPROP 2 LAST SIG_NAME SMB_M2_ALT_N
J 0
(-3150 3710);
DISPLAY 0.617021 (-3150 3710);
PAINT ORANGE (-3150 3710);
FORCEPROP 2 LASTPROP $XR0 185 
J 0
(-3306 3700);
DISPLAY 0.638298 (-3306 3700);
PAINT MONO (-3306 3700);
WIRE 16 -1 (-2050 2925)(-2750 2925);
FORCEPROP 2 LAST SIG_NAME SMB_M2_SCL_R
J 0
(-2660 2935);
DISPLAY 0.617021 (-2660 2935);
PAINT ORANGE (-2660 2935);
FORCEPROP 2 LASTPROP $XRERR UNIQUE?
J 0
(-2900 2935);
DISPLAY 0.638298 (-2900 2935);
PAINT MONO (-2900 2935);
DISPLAY INVISIBLE (-2900 2935);
WIRE 16 -1 (-7450 3450)(-6750 3450);
FORCEPROP 2 LAST SIG_NAME SMB_M2_SDA
J 0
(-7435 3460);
DISPLAY 0.638298 (-7435 3460);
PAINT ORANGE (-7435 3460);
FORCEPROP 2 LASTPROP $XR0 185 
J 0
(-7546 3450);
DISPLAY 0.638298 (-7546 3450);
PAINT MONO (-7546 3450);
WIRE 16 -1 (-6150 4100)(-3550 4100);
FORCEPROP 2 LAST SIG_NAME P3E_PCH_M2_RX_DN<2>
J 2
(-3575 4110);
DISPLAY 0.617021 (-3575 4110);
PAINT ORANGE (-3575 4110);
WIRE 16 -1 (-3550 4050)(-6150 4050);
FORCEPROP 2 LAST SIG_NAME P3E_PCH_M2_RX_DP<2>
J 2
(-3575 4060);
DISPLAY 0.617021 (-3575 4060);
PAINT ORANGE (-3575 4060);
WIRE 16 -1 (-3550 3800)(-6150 3800);
FORCEPROP 2 LAST SIG_NAME P3E_PCH_M2_RX_DN<1>
J 2
(-3575 3810);
DISPLAY 0.617021 (-3575 3810);
PAINT ORANGE (-3575 3810);
WIRE 16 -1 (-6150 3750)(-3550 3750);
FORCEPROP 2 LAST SIG_NAME P3E_PCH_M2_RX_DP<1>
J 2
(-3575 3760);
DISPLAY 0.617021 (-3575 3760);
PAINT ORANGE (-3575 3760);
WIRE 16 -1 (-4950 3600)(-6150 3600);
FORCEPROP 2 LAST SIG_NAME P3E_PCH_M2_TX_C_DP<1>
J 0
(-5900 3610);
DISPLAY 0.617021 (-5900 3610);
PAINT ORANGE (-5900 3610);
FORCEPROP 2 LASTPROP $XRERR UNIQUE?
J 0
(-6140 3610);
DISPLAY 0.638298 (-6140 3610);
PAINT MONO (-6140 3610);
DISPLAY INVISIBLE (-6140 3610);
WIRE 16 -1 (-7500 3250)(-6750 3250);
FORCEPROP 0 LAST SIG_NAME RST_PCIE_M2_DEV_IC_N
J 0
(-7450 3260);
DISPLAY 0.617021 (-7450 3260);
PAINT ORANGE (-7450 3260);
WIRE 16 -1 (-8000 3200)(-8000 3400);
WIRE 16 -1 (-8000 3200)(-6750 3200);
FORCEPROP 0 LAST SIG_NAME PU_M2_CLK_REQ_N
J 0
(-7450 3210);
DISPLAY 0.617021 (-7450 3210);
PAINT ORANGE (-7450 3210);
FORCEPROP 2 LASTPROP $XRERR UNIQUE?
J 0
(-7690 3210);
DISPLAY 0.638298 (-7690 3210);
PAINT MONO (-7690 3210);
DISPLAY INVISIBLE (-7690 3210);
WIRE 3 682 (-7000 3050)(-6950 3050);
WIRE 3 682 (-7000 3950)(-7000 3050);
WIRE 3 682 (-7000 3950)(-7050 3950);
WIRE 3 682 (-6925 4000)(-7000 4000);
WIRE 3 682 (-7000 4000)(-7000 3950);
WIRE 16 -1 (-7450 3400)(-6750 3400);
FORCEPROP 2 LAST SIG_NAME SMB_M2_ALT_N
J 0
(-7435 3410);
DISPLAY 0.638298 (-7435 3410);
PAINT ORANGE (-7435 3410);
FORCEPROP 2 LASTPROP $XR0 185 
J 0
(-7666 3400);
DISPLAY 0.638298 (-7666 3400);
PAINT MONO (-7666 3400);
WIRE 16 -1 (-7450 3550)(-6750 3550);
FORCEPROP 2 LAST SIG_NAME TP_M2_DEVSLP
J 0
(-7450 3560);
DISPLAY 0.617021 (-7450 3560);
PAINT ORANGE (-7450 3560);
FORCEPROP 2 LASTPROP $XRERR UNIQUE?
J 0
(-7690 3550);
DISPLAY 0.638298 (-7690 3550);
PAINT MONO (-7690 3550);
DISPLAY INVISIBLE (-7690 3550);
WIRE 3 682 (-7500 3500)(-7550 3500);
WIRE 3 682 (-7650 3450)(-7650 3800);
WIRE 3 682 (-7550 3450)(-7650 3450);
WIRE 3 682 (-7550 3500)(-7550 3450);
WIRE 3 682 (-7550 3450)(-7550 3400);
WIRE 3 682 (-7550 3400)(-7500 3400);
WIRE 16 -1 (-2675 1825)(-3525 1825);
FORCEPROP 2 LAST SIG_NAME P3E_PCH_TX_0_DP
J 0
(-3485 1835);
DISPLAY 0.617021 (-3485 1835);
PAINT ORANGE (-3485 1835);
WIRE 16 -1 (-2675 500)(-3525 500);
FORCEPROP 2 LAST SIG_NAME P3E_PCH_RX_0_DN
J 0
(-3485 510);
DISPLAY 0.617021 (-3485 510);
PAINT ORANGE (-3485 510);
WIRE 16 -1 (-3500 2925)(-2950 2925);
FORCEPROP 2 LAST SIG_NAME SMB_M2_SCL
J 0
(-3485 2935);
DISPLAY 0.617021 (-3485 2935);
PAINT ORANGE (-3485 2935);
FORCEPROP 2 LASTPROP $XR0 185 
J 0
(-3626 2925);
DISPLAY 0.638298 (-3626 2925);
PAINT MONO (-3626 2925);
WIRE 16 -1 (-3500 2875)(-2725 2875);
FORCEPROP 2 LAST SIG_NAME SMB_M2_SDA
J 0
(-3485 2885);
DISPLAY 0.617021 (-3485 2885);
PAINT ORANGE (-3485 2885);
FORCEPROP 2 LASTPROP $XR0 185 
J 0
(-3626 2875);
DISPLAY 0.638298 (-3626 2875);
PAINT MONO (-3626 2875);
WIRE 16 -1 (-5325 1675)(-5425 1675);
WIRE 16 -1 (-5325 1875)(-5425 1875);
WIRE 16 -1 (-5325 1875)(-5325 1675);
WIRE 16 -1 (-4600 1675)(-5325 1675);
WIRE 16 -1 (-5425 1875)(-5425 1775);
WIRE 16 -1 (-5425 1675)(-5425 1775);
WIRE 16 -1 (-5425 1775)(-4600 1775);
WIRE 16 -1 (-4600 1775)(-4600 1675);
WIRE 16 -1 (-4600 1875)(-5325 1875);
WIRE 16 -1 (-4600 1875)(-4600 1775);
WIRE 16 -1 (-4400 2500)(-4350 2500);
WIRE 16 -1 (-4400 2700)(-4400 2500);
WIRE 16 -1 (-5000 2500)(-4400 2500);
FORCEPROP 0 LAST SIG_NAME FM_M2_DET_LVC3
J 0
(-4885 2510);
DISPLAY 0.617021 (-4885 2510);
PAINT ORANGE (-4885 2510);
FORCEPROP 2 LASTPROP $XRERR UNIQUE?
J 0
(-5125 2510);
DISPLAY 0.638298 (-5125 2510);
PAINT MONO (-5125 2510);
DISPLAY INVISIBLE (-5125 2510);
WIRE 16 -1 (-5150 1350)(-5150 1250);
WIRE 16 -1 (-5450 1350)(-5450 1250);
WIRE 16 -1 (-5450 1350)(-5150 1350);
WIRE 16 -1 (-5750 1350)(-5750 1250);
WIRE 16 -1 (-5750 1350)(-5450 1350);
WIRE 16 -1 (-6150 1350)(-5750 1350);
FORCEPROP 2 LAST SIG_NAME P1V8_M2
J 0
(-6135 1360);
DISPLAY 1.021277 (-6135 1360);
PAINT ORANGE (-6135 1360);
FORCEPROP 2 LASTPROP $XR0 185 
J 0
(-6246 1350);
DISPLAY 0.638298 (-6246 1350);
PAINT MONO (-6246 1350);
WIRE 16 -1 (-4825 850)(-5450 850);
FORCEPROP 2 LAST SIG_NAME SMB_M2_SDA
J 0
(-5085 860);
DISPLAY 0.617021 (-5085 860);
PAINT ORANGE (-5085 860);
FORCEPROP 2 LASTPROP $XR0 185 
J 0
(-4765 850);
DISPLAY 0.638298 (-4765 850);
PAINT MONO (-4765 850);
WIRE 16 -1 (-5450 1050)(-5450 850);
WIRE 16 -1 (-5750 800)(-4825 800);
FORCEPROP 2 LAST SIG_NAME SMB_M2_SCL
J 0
(-5085 810);
DISPLAY 0.617021 (-5085 810);
PAINT ORANGE (-5085 810);
FORCEPROP 2 LASTPROP $XR0 185 
J 0
(-4765 800);
DISPLAY 0.638298 (-4765 800);
PAINT MONO (-4765 800);
WIRE 16 -1 (-5750 1050)(-5750 800);
WIRE 16 -1 (-7800 1500)(-7800 1450);
WIRE 16 -1 (-7800 1550)(-7800 1500);
WIRE 16 -1 (-7250 1500)(-7800 1500);
FORCEPROP 2 LAST SIG_NAME VREF_LMV431_1V42
J 0
(-7735 1510);
DISPLAY 0.638298 (-7735 1510);
PAINT ORANGE (-7735 1510);
FORCEPROP 2 LASTPROP $XRERR UNIQUE?
J 0
(-7975 1510);
DISPLAY 0.638298 (-7975 1510);
PAINT MONO (-7975 1510);
DISPLAY INVISIBLE (-7975 1510);
WIRE 16 -1 (-675 2925)(-1400 2925);
FORCEPROP 0 LAST SIG_NAME SMB_OCP_LAN_STBY_LVC3_SCL
J 0
(-1300 2935);
DISPLAY 0.617021 (-1300 2935);
PAINT ORANGE (-1300 2935);
WIRE 16 -1 (-4750 3900)(-3550 3900);
FORCEPROP 2 LAST SIG_NAME P3E_PCH_M2_TX_DP<2>
J 2
(-3575 3910);
DISPLAY 0.617021 (-3575 3910);
PAINT ORANGE (-3575 3910);
WIRE 16 -1 (-4750 3650)(-3550 3650);
FORCEPROP 2 LAST SIG_NAME P3E_PCH_M2_TX_DN<1>
J 2
(-3575 3660);
DISPLAY 0.617021 (-3575 3660);
PAINT ORANGE (-3575 3660);
WIRE 16 -1 (-4750 3600)(-3550 3600);
FORCEPROP 2 LAST SIG_NAME P3E_PCH_M2_TX_DP<1>
J 2
(-3575 3610);
DISPLAY 0.617021 (-3575 3610);
PAINT ORANGE (-3575 3610);
WIRE 16 -1 (-3525 2100)(-2700 2100);
FORCEPROP 2 LAST SIG_NAME SATA6G_S0_TX_DP
J 0
(-3510 2110);
DISPLAY 0.617021 (-3510 2110);
PAINT ORANGE (-3510 2110);
WIRE 16 -1 (-2475 1825)(-1750 1825);
WIRE 16 -1 (-1750 1825)(-1750 2100);
WIRE 16 -1 (-1750 2100)(-1200 2100);
FORCEPROP 2 LAST SIG_NAME P3E_PCH_M2_SATA6G_TX_R_DP
J 2
(-1225 2110);
DISPLAY 0.617021 (-1225 2110);
PAINT ORANGE (-1225 2110);
WIRE 16 -1 (-2500 2100)(-1750 2100);
WIRE 8 682 (-4150 2300)(-4150 400);
WIRE 8 682 (-250 2300)(-4150 2300);
WIRE 8 682 (-4150 400)(-250 400);
WIRE 8 682 (-250 400)(-250 2300);
WIRE 16 -1 (-2475 750)(-1775 750);
WIRE 16 -1 (-1775 750)(-1200 750);
FORCEPROP 2 LAST SIG_NAME P3E_PCH_M2_SATA6G_RX_R_DN
J 2
(-1250 760);
DISPLAY 0.617021 (-1250 760);
PAINT ORANGE (-1250 760);
WIRE 16 -1 (-1775 500)(-1775 750);
WIRE 16 -1 (-2475 500)(-1775 500);
WIRE 16 -1 (-2500 950)(-1775 950);
WIRE 16 -1 (-1775 950)(-1775 1175);
WIRE 16 -1 (-1775 1175)(-1200 1175);
FORCEPROP 2 LAST SIG_NAME P3E_PCH_M2_SATA6G_RX_R_DP
J 2
(-1250 1185);
DISPLAY 0.617021 (-1250 1185);
PAINT ORANGE (-1250 1185);
WIRE 16 -1 (-2500 1175)(-1775 1175);
DOT 1 (-1775 1175);
DOT 1 (-7550 3450);
DOT 1 (-5450 1350);
DOT 1 (-7800 1800);
DOT 1 (-5425 1775);
DOT 1 (-5325 1675);
DOT 1 (-5325 1875);
DOT 1 (-4400 2500);
DOT 1 (-5500 2500);
DOT 1 (-4000 4425);
DOT 1 (-4250 4725);
DOT 1 (-4000 4725);
DOT 1 (-2925 4425);
DOT 1 (-2925 4725);
DOT 1 (-2675 4425);
DOT 1 (-2675 4725);
DOT 1 (-1450 4425);
DOT 1 (-1450 4725);
DOT 1 (-1200 4425);
DOT 1 (-1200 4725);
DOT 1 (-4250 4425);
DOT 1 (-7550 2900);
DOT 1 (-7550 2850);
DOT 1 (-7000 3950);
DOT 1 (-6000 2650);
DOT 1 (-6000 2800);
DOT 1 (-6000 2850);
DOT 1 (-7550 4100);
DOT 1 (-7550 4200);
DOT 1 (-7550 4150);
DOT 1 (-7550 4450);
DOT 1 (-7550 4400);
DOT 1 (-6000 4550);
DOT 1 (-6000 4650);
DOT 1 (-1325 3600);
DOT 1 (-1150 3350);
DOT 1 (-1300 4125);
DOT 1 (-1750 2100);
DOT 1 (-1775 1600);
DOT 1 (-1775 750);
DOT 1 (-4600 1775);
DOT 1 (-5750 1350);
DOT 1 (-7900 1050);
DOT 1 (-7800 1500);
DOT 1 (-7300 1050);
FORCENOTE
POP_M2_SATA
(-2700 1725) 0;
DISPLAY LEFT (-2700 1725);
DISPLAY 0.638298 (-2700 1725);
PAINT PURPLE (-2700 1725);
FORCENOTE
POP_M2_PCIE
(-2725 1475) 0;
DISPLAY LEFT (-2725 1475);
DISPLAY 0.638298 (-2725 1475);
PAINT PURPLE (-2725 1475);
FORCENOTE
POP_M2_PCIE
(-2700 1050) 0;
DISPLAY LEFT (-2700 1050);
DISPLAY 0.638298 (-2700 1050);
PAINT PURPLE (-2700 1050);
FORCENOTE
POP_M2_SATA
(-2700 875) 0;
DISPLAY LEFT (-2700 875);
DISPLAY 0.638298 (-2700 875);
PAINT PURPLE (-2700 875);
FORCENOTE
POP_M2_PCIE
(-2700 600) 0;
DISPLAY LEFT (-2700 600);
DISPLAY 0.638298 (-2700 600);
PAINT PURPLE (-2700 600);
FORCENOTE
M.2 PCIE POP: C8F7, C8F12, R8F18 AND R8F21
(-2550 350) 0;
DISPLAY LEFT (-2550 350);
DISPLAY 1.021277 (-2550 350);
PAINT PURPLE (-2550 350);
FORCENOTE
POP_M2_SATA
(-2700 2225) 0;
DISPLAY LEFT (-2700 2225);
DISPLAY 0.638298 (-2700 2225);
PAINT PURPLE (-2700 2225);
FORCENOTE
POP_M2_PCIE
(-2700 1925) 0;
DISPLAY LEFT (-2700 1925);
DISPLAY 0.638298 (-2700 1925);
PAINT PURPLE (-2700 1925);
FORCENOTE
TP FAB3 ADD M2 I2C CIRCUIT 0831
(-7925 3825) 0;
DISPLAY LEFT (-7925 3825);
DISPLAY 0.638298 (-7925 3825);
PAINT RED (-7925 3825);
FORCENOTE
TP FAB1 DEL NETS 0309
(-7525 3950) 0;
DISPLAY LEFT (-7525 3950);
DISPLAY 0.638298 (-7525 3950);
PAINT RED (-7525 3950);
FORCENOTE
ROOM=M_2
(-7950 325) 0;
DISPLAY LEFT (-7950 325);
DISPLAY 1.021277 (-7950 325);
PAINT PURPLE (-7950 325);
FORCENOTE
TP FAB1 CHANGE RESET SIGNAL FROM RESET IC 1204
(-7712 2431) 0;
DISPLAY LEFT (-7712 2431);
DISPLAY 1.021277 (-7712 2431);
PAINT RED (-7712 2431);
FORCENOTE
0  M.2 SATA SSD
(-5400 1800) 0;
DISPLAY LEFT (-5400 1800);
DISPLAY 1.021277 (-5400 1800);
PAINT PURPLE (-5400 1800);
FORCENOTE
POP_M2_SATA
(-2700 1275) 0;
DISPLAY LEFT (-2700 1275);
DISPLAY 0.638298 (-2700 1275);
PAINT PURPLE (-2700 1275);
FORCENOTE
BOM_COST=ST_FLASH
(-7950 225) 0;
DISPLAY LEFT (-7950 225);
DISPLAY 1.021277 (-7950 225);
PAINT PURPLE (-7950 225);
FORCENOTE
PCH
(-4100 1275) 0;
DISPLAY LEFT (-4100 1275);
DISPLAY 1.595745 (-4100 1275);
PAINT PURPLE (-4100 1275);
FORCENOTE
M.2 CONNECTOR
(-1050 1325) 0;
DISPLAY LEFT (-1050 1325);
DISPLAY 1.595745 (-1050 1325);
PAINT PURPLE (-1050 1325);
FORCENOTE
1  M.2 PCIE SSD
(-5400 1700) 0;
DISPLAY LEFT (-5400 1700);
DISPLAY 1.021277 (-5400 1700);
PAINT PURPLE (-5400 1700);
FORCENOTE
TP FAB3 ADD M2 I2C CIRCUIT 0831
(-8000 575) 0;
DISPLAY LEFT (-8000 575);
DISPLAY 1.021277 (-8000 575);
PAINT RED (-8000 575);
FORCENOTE
TP FAB1 CHANGE CONN PN TO 062.10003.0B21
(-6950 2350) 0;
DISPLAY LEFT (-6950 2350);
DISPLAY 1.021277 (-6950 2350);
PAINT RED (-6950 2350);
FORCENOTE
TP FAB1 DEL NET 0309
(-5850 3000) 0;
DISPLAY LEFT (-5850 3000);
DISPLAY 1.021277 (-5850 3000);
PAINT RED (-5850 3000);
FORCENOTE
M.2 SATA POP: C8F6, C8F11, C8F13 AND C8F15
(-4150 350) 0;
DISPLAY LEFT (-4150 350);
DISPLAY 1.021277 (-4150 350);
PAINT PURPLE (-4150 350);
FORCENOTE
TP FAB3 ADD M2 I2C CIRCUIT 0831
(-3200 2375) 0;
DISPLAY LEFT (-3200 2375);
DISPLAY 1.021277 (-3200 2375);
PAINT RED (-3200 2375);
QUIT
